FILE_TYPE = MACRO_DRAWING;
SET COLOR_WIRE YELLOW;
SET COLOR_PROP ORANGE;
SET COLOR_DOT WHITE;
SET COLOR_ARC YELLOW;
SET COLOR_BODY GREEN;
SET COLOR_NOTE PURPLE;
SET PROP_DISPLAY VALUE;
SET PAGE_NUMBER P323;
FORCEADD OFFPAGE..1
(-1600 -1325);
PAINT AQUA (-1600 -1325);
FORCEPROP 2 LAST $XR2 193 
J 0
(-2122 -1325);
DISPLAY 0.638298 (-2122 -1325);
PAINT MONO (-2122 -1325);
FORCEPROP 2 LAST $XR1 192 
J 0
(-2002 -1325);
DISPLAY 0.638298 (-2002 -1325);
PAINT MONO (-2002 -1325);
FORCEPROP 2 LAST $XR0 191 
J 0
(-1882 -1325);
DISPLAY 0.638298 (-1882 -1325);
PAINT MONO (-1882 -1325);
FORCEPROP 2 LAST CDS_LIB standard
J 0
(-1600 -1325);
DISPLAY INVISIBLE (-1600 -1325);
FORCEPROP 1 LAST OFFPAGE TRUE
J 0
(-1275 -1450);
DISPLAY 0.872340 (-1275 -1450);
PAINT AQUA (-1275 -1450);
DISPLAY INVISIBLE (-1275 -1450);
FORCEPROP 1 LAST COMMENT_BODY TRUE
J 0
(-1475 -1425);
DISPLAY 0.872340 (-1475 -1425);
PAINT GREEN (-1475 -1425);
DISPLAY INVISIBLE (-1475 -1425);
FORCEPROP 2 LAST PATH I1
J 0
(-1875 -1275);
DISPLAY 1.021277 (-1875 -1275);
DISPLAY INVISIBLE (-1875 -1275);
FORCEADD UNIVERSAL_POWER..1
R 2
(-450 -725);
FORCEPROP 3 LASTPIN (-450 -775) SIG_NAME P3V3_AUX\g
J 0
(-440 -765);
DISPLAY 0.659574 (-440 -765);
PAINT MONO (-440 -765);
DISPLAY INVISIBLE (-440 -765);
FORCEPROP 1 LAST HDL_POWER P3V3_AUX
J 1
(-450 -675);
DISPLAY 0.510638 (-450 -675);
PAINT GREEN (-450 -675);
FORCEPROP 2 LAST CDS_LIB logical_power
J 0
(-450 -725);
DISPLAY INVISIBLE (-450 -725);
FORCEPROP 1 LAST PATH I10
J 2
(-500 -700);
DISPLAY 0.872340 (-500 -700);
PAINT AQUA (-500 -700);
DISPLAY INVISIBLE (-500 -700);
FORCEADD UNIVERSAL_GND..1
(-1100 -2000);
FORCEPROP 3 LASTPIN (-1100 -1950) SIG_NAME GND\g
J 0
(-1090 -1940);
DISPLAY 0.659574 (-1090 -1940);
PAINT MONO (-1090 -1940);
DISPLAY INVISIBLE (-1090 -1940);
FORCEPROP 2 LAST CDS_LIB logical_power
J 0
(-1100 -2000);
DISPLAY INVISIBLE (-1100 -2000);
FORCEPROP 1 LAST HDL_POWER GND
J 1
(-1075 -2075);
DISPLAY 0.872340 (-1075 -2075);
PAINT GREEN (-1075 -2075);
DISPLAY INVISIBLE (-1075 -2075);
FORCEPROP 1 LAST PATH I2
J 0
(-1025 -2000);
DISPLAY 0.872340 (-1025 -2000);
PAINT AQUA (-1025 -2000);
DISPLAY INVISIBLE (-1025 -2000);
FORCEADD UNIVERSAL_GND..1
(1625 -2125);
FORCEPROP 3 LASTPIN (1625 -2075) SIG_NAME GND\g
J 0
(1635 -2065);
DISPLAY 0.659574 (1635 -2065);
PAINT MONO (1635 -2065);
DISPLAY INVISIBLE (1635 -2065);
FORCEPROP 2 LAST CDS_LIB logical_power
J 0
(1625 -2125);
DISPLAY INVISIBLE (1625 -2125);
FORCEPROP 1 LAST HDL_POWER GND
J 1
(1650 -2200);
DISPLAY 0.872340 (1650 -2200);
PAINT GREEN (1650 -2200);
DISPLAY INVISIBLE (1650 -2200);
FORCEPROP 1 LAST PATH I28
J 0
(1700 -2125);
DISPLAY 0.872340 (1700 -2125);
PAINT AQUA (1700 -2125);
DISPLAY INVISIBLE (1700 -2125);
FORCEADD UNIVERSAL_GND..1
(125 -2000);
FORCEPROP 3 LASTPIN (125 -1950) SIG_NAME GND\g
J 0
(135 -1940);
DISPLAY 0.659574 (135 -1940);
PAINT MONO (135 -1940);
DISPLAY INVISIBLE (135 -1940);
FORCEPROP 2 LAST CDS_LIB logical_power
J 0
(125 -2000);
DISPLAY INVISIBLE (125 -2000);
FORCEPROP 1 LAST HDL_POWER GND
J 1
(150 -2075);
DISPLAY 0.872340 (150 -2075);
PAINT GREEN (150 -2075);
DISPLAY INVISIBLE (150 -2075);
FORCEPROP 1 LAST PATH I29
J 0
(200 -2000);
DISPLAY 0.872340 (200 -2000);
PAINT AQUA (200 -2000);
DISPLAY INVISIBLE (200 -2000);
FORCEADD Q_CAP..1
(-1100 -1625);
FORCEPROP 1 LAST PART_NUMBER CH0396J0B04
J 0
(-1025 -1700);
DISPLAY 0.510638 (-1025 -1700);
DISPLAY INVISIBLE (-1025 -1700);
FORCEPROP 1 LAST VOLTAGE 50V
J 0
(-1025 -1650);
DISPLAY 0.510638 (-1025 -1650);
FORCEPROP 2 LAST ROOM E1S1_P3V3_BOM2
J 0
(-1025 -1550);
DISPLAY 0.510638 (-1025 -1550);
FORCEPROP 1 LAST MATERIAL EMPTY
J 0
(-1025 -1675);
DISPLAY 0.510638 (-1025 -1675);
PAINT RED (-1025 -1675);
FORCEPROP 1 LAST VALUE 39PF
J 0
(-1025 -1625);
DISPLAY 0.510638 (-1025 -1625);
FORCEPROP 1 LAST PACK_TYPE C0402
J 0
(-1025 -1725);
DISPLAY 0.510638 (-1025 -1725);
FORCEPROP 1 LAST LOCATION PC2197
J 0
(-1025 -1600);
DISPLAY 0.510638 (-1025 -1600);
FORCEPROP 1 LAST TOLERANCE 5%
J 0
(-1050 -1675);
DISPLAY 0.723404 (-1050 -1675);
PAINT SKYBLUE (-1050 -1675);
DISPLAY INVISIBLE (-1050 -1675);
FORCEPROP 2 LAST CDS_LIB pure_quanta
J 0
(-1100 -1625);
DISPLAY INVISIBLE (-1100 -1625);
FORCEPROP 1 LAST PATH I3
J 0
(-1050 -1475);
DISPLAY 0.978723 (-1050 -1475);
PAINT WHITE (-1050 -1475);
DISPLAY INVISIBLE (-1050 -1475);
FORCEPROP 0 LAST $SEC 1
J 0
(-1050 -1500);
DISPLAY INVISIBLE (-1050 -1500);
FORCEPROP 0 LAST CDS_SEC 1
J 0
(-1050 -1500);
DISPLAY INVISIBLE (-1050 -1500);
FORCEPROP 1 LASTPIN (-1100 -1525) $PN 1
J 0
(-1090 -1545);
DISPLAY 0.787234 (-1090 -1545);
PAINT MONO (-1090 -1545);
DISPLAY INVISIBLE (-1090 -1545);
FORCEPROP 1 LASTPIN (-1100 -1725) $PN 2
J 0
(-1090 -1745);
DISPLAY 0.787234 (-1090 -1745);
PAINT MONO (-1090 -1745);
DISPLAY INVISIBLE (-1090 -1745);
FORCEADD Q_CAP..1
(125 -1700);
FORCEPROP 1 LAST PART_NUMBER CH3683K1B09
J 0
(200 -1750);
DISPLAY 0.510638 (200 -1750);
DISPLAY INVISIBLE (200 -1750);
FORCEPROP 1 LAST VALUE 0.068UF
J 0
(200 -1675);
DISPLAY 0.510638 (200 -1675);
FORCEPROP 1 LAST VOLTAGE 16V
J 0
(200 -1700);
DISPLAY 0.510638 (200 -1700);
FORCEPROP 1 LAST MATERIAL EMPTY
J 0
(200 -1725);
DISPLAY 0.510638 (200 -1725);
PAINT RED (200 -1725);
FORCEPROP 1 LAST PACK_TYPE 0402
J 0
(200 -1775);
DISPLAY 0.510638 (200 -1775);
FORCEPROP 2 LAST ROOM E1S1_P3V3_BOM2
J 0
(200 -1600);
DISPLAY 0.510638 (200 -1600);
FORCEPROP 1 LAST LOCATION PC2201
J 0
(200 -1650);
DISPLAY 0.510638 (200 -1650);
FORCEPROP 1 LAST TOLERANCE 10%
J 0
(175 -1750);
DISPLAY 0.723404 (175 -1750);
PAINT SKYBLUE (175 -1750);
DISPLAY INVISIBLE (175 -1750);
FORCEPROP 2 LAST CDS_LIB pure_quanta
J 0
(125 -1700);
DISPLAY INVISIBLE (125 -1700);
FORCEPROP 1 LAST PATH I30
J 0
(175 -1550);
DISPLAY 0.978723 (175 -1550);
PAINT WHITE (175 -1550);
DISPLAY INVISIBLE (175 -1550);
FORCEPROP 0 LAST $SEC 1
J 0
(175 -1550);
DISPLAY INVISIBLE (175 -1550);
FORCEPROP 0 LAST CDS_SEC 1
J 0
(175 -1550);
DISPLAY INVISIBLE (175 -1550);
FORCEPROP 1 LASTPIN (125 -1600) $PN 1
J 0
(135 -1620);
DISPLAY 0.787234 (135 -1620);
PAINT MONO (135 -1620);
DISPLAY INVISIBLE (135 -1620);
FORCEPROP 1 LASTPIN (125 -1800) $PN 2
J 0
(135 -1820);
DISPLAY 0.787234 (135 -1820);
PAINT MONO (135 -1820);
DISPLAY INVISIBLE (135 -1820);
FORCEADD MP5016GQHLZ..1
(775 -1375);
FORCEPROP 1 LAST PART_NUMBER AL005016007
J 0
(530 -1041);
DISPLAY 0.510638 (530 -1041);
PAINT GREEN (530 -1041);
DISPLAY INVISIBLE (530 -1041);
FORCEPROP 1 LAST MATERIAL EMPTY
J 0
(530 -1168);
DISPLAY 0.510638 (530 -1168);
PAINT RED (530 -1168);
FORCEPROP 2 LAST VALUE MP5016GQH-L-Z
J 0
(525 -1000);
DISPLAY 0.510638 (525 -1000);
FORCEPROP 2 LAST PART_TYPE SMLF
J 0
(525 -950);
DISPLAY 0.510638 (525 -950);
FORCEPROP 2 LAST ROOM E1S1_P3V3_BOM2
J 0
(525 -850);
DISPLAY 0.510638 (525 -850);
FORCEPROP 1 LAST LOCATION PU293
J 0
(525 -900);
DISPLAY 0.510638 (525 -900);
PAINT GREEN (525 -900);
FORCEPROP 0 LASTPIN (375 -1525) $PN 10
J 2
(365 -1515);
DISPLAY 0.510638 (365 -1515);
FORCEPROP 0 LASTPIN (375 -1325) $PN 9
J 2
(365 -1315);
DISPLAY 0.510638 (365 -1315);
FORCEPROP 0 LASTPIN (1175 -1425) $PN 8
J 0
(1185 -1415);
DISPLAY 0.510638 (1185 -1415);
FORCEPROP 0 LASTPIN (1175 -1525) $PN 3
J 0
(1185 -1515);
DISPLAY 0.510638 (1185 -1515);
FORCEPROP 0 LASTPIN (375 -1475) $PN 4
J 2
(365 -1465);
DISPLAY 0.510638 (365 -1465);
FORCEPROP 0 LASTPIN (375 -1425) $PN 5
J 2
(365 -1415);
DISPLAY 0.510638 (365 -1415);
FORCEPROP 0 LASTPIN (1175 -1225) $PN 6_7
J 0
(1185 -1215);
DISPLAY 0.510638 (1185 -1215);
FORCEPROP 0 LASTPIN (375 -1225) $PN 1_2
J 2
(365 -1215);
DISPLAY 0.510638 (365 -1215);
FORCEPROP 1 LAST NEEDS_NO_SIZE TRUE
J 0
(775 -1375);
DISPLAY 0.723404 (775 -1375);
PAINT GREEN (775 -1375);
DISPLAY INVISIBLE (775 -1375);
FORCEPROP 1 LAST CDS_LMAN_SYM_OUTLINE -250,200,250,-200
J 0
(775 -1375);
DISPLAY 0.468085 (775 -1375);
PAINT GREEN (775 -1375);
DISPLAY INVISIBLE (775 -1375);
FORCEPROP 2 LAST CDS_LIB pure_quanta
J 0
(775 -1375);
DISPLAY INVISIBLE (775 -1375);
FORCEPROP 1 LAST PATH I31
J 0
(775 -1375);
DISPLAY 0.723404 (775 -1375);
PAINT GREEN (775 -1375);
DISPLAY INVISIBLE (775 -1375);
FORCEPROP 0 LAST $SEC 1
J 0
(550 -750);
DISPLAY INVISIBLE (550 -750);
FORCEPROP 0 LAST CDS_SEC 1
J 0
(550 -750);
DISPLAY INVISIBLE (550 -750);
FORCEADD Q_CAP..1
(1625 -1775);
FORCEPROP 1 LAST PART_NUMBER CH11006JB18
J 0
(1700 -1825);
DISPLAY 0.510638 (1700 -1825);
DISPLAY INVISIBLE (1700 -1825);
FORCEPROP 1 LAST TOLERANCE 5%
J 0
(1700 -1775);
DISPLAY 0.510638 (1700 -1775);
FORCEPROP 1 LAST VOLTAGE 50V
J 0
(1700 -1750);
DISPLAY 0.510638 (1700 -1750);
FORCEPROP 1 LAST MATERIAL EMPTY
J 0
(1700 -1800);
DISPLAY 0.510638 (1700 -1800);
PAINT RED (1700 -1800);
FORCEPROP 1 LAST PACK_TYPE 0402
J 0
(1700 -1850);
DISPLAY 0.510638 (1700 -1850);
FORCEPROP 1 LAST VALUE 100PF
J 0
(1700 -1725);
DISPLAY 0.510638 (1700 -1725);
FORCEPROP 2 LAST ROOM E1S1_P3V3_BOM2
J 0
(1700 -1650);
DISPLAY 0.510638 (1700 -1650);
FORCEPROP 1 LAST LOCATION PC2203
J 0
(1700 -1700);
DISPLAY 0.510638 (1700 -1700);
FORCEPROP 2 LAST CDS_LIB pure_quanta
J 0
(1625 -1775);
DISPLAY INVISIBLE (1625 -1775);
FORCEPROP 1 LAST PATH I32
J 0
(1675 -1625);
DISPLAY 0.978723 (1675 -1625);
PAINT WHITE (1675 -1625);
DISPLAY INVISIBLE (1675 -1625);
FORCEPROP 0 LAST $SEC 1
J 0
(1675 -1625);
DISPLAY INVISIBLE (1675 -1625);
FORCEPROP 0 LAST CDS_SEC 1
J 0
(1675 -1625);
DISPLAY INVISIBLE (1675 -1625);
FORCEPROP 1 LASTPIN (1625 -1675) $PN 1
J 0
(1635 -1695);
DISPLAY 0.787234 (1635 -1695);
PAINT MONO (1635 -1695);
DISPLAY INVISIBLE (1635 -1695);
FORCEPROP 1 LASTPIN (1625 -1875) $PN 2
J 0
(1635 -1895);
DISPLAY 0.787234 (1635 -1895);
PAINT MONO (1635 -1895);
DISPLAY INVISIBLE (1635 -1895);
FORCEADD UNIVERSAL_GND..1
(2225 -1900);
FORCEPROP 3 LASTPIN (2225 -1850) SIG_NAME GND\g
J 0
(2235 -1840);
DISPLAY 0.659574 (2235 -1840);
PAINT MONO (2235 -1840);
DISPLAY INVISIBLE (2235 -1840);
FORCEPROP 2 LAST CDS_LIB logical_power
J 0
(2225 -1900);
DISPLAY INVISIBLE (2225 -1900);
FORCEPROP 1 LAST HDL_POWER GND
J 1
(2250 -1975);
DISPLAY 0.872340 (2250 -1975);
PAINT GREEN (2250 -1975);
DISPLAY INVISIBLE (2250 -1975);
FORCEPROP 1 LAST PATH I33
J 0
(2300 -1900);
DISPLAY 0.872340 (2300 -1900);
PAINT AQUA (2300 -1900);
DISPLAY INVISIBLE (2300 -1900);
FORCEADD Q_CAP..1
(2225 -1550);
FORCEPROP 1 LAST PART_NUMBER CH6103KEA01
J 0
(2300 -1600);
DISPLAY 0.510638 (2300 -1600);
DISPLAY INVISIBLE (2300 -1600);
FORCEPROP 1 LAST MATERIAL EMPTY
J 0
(2300 -1575);
DISPLAY 0.510638 (2300 -1575);
PAINT RED (2300 -1575);
FORCEPROP 1 LAST PACK_TYPE C0805
J 0
(2300 -1625);
DISPLAY 0.510638 (2300 -1625);
FORCEPROP 1 LAST VOLTAGE 16V
J 0
(2300 -1550);
DISPLAY 0.510638 (2300 -1550);
FORCEPROP 1 LAST VALUE 10UF
J 0
(2300 -1525);
DISPLAY 0.510638 (2300 -1525);
FORCEPROP 2 LAST ROOM E1S1_P3V3_BOM2
J 0
(2300 -1450);
DISPLAY 0.510638 (2300 -1450);
FORCEPROP 1 LAST LOCATION PC2204
J 0
(2300 -1500);
DISPLAY 0.510638 (2300 -1500);
FORCEPROP 2 LAST CDS_LIB pure_quanta
J 0
(2225 -1550);
DISPLAY INVISIBLE (2225 -1550);
FORCEPROP 1 LAST TOLERANCE 10%
J 0
(2275 -1600);
DISPLAY 0.723404 (2275 -1600);
PAINT SKYBLUE (2275 -1600);
DISPLAY INVISIBLE (2275 -1600);
FORCEPROP 1 LAST PATH I34
J 0
(2275 -1400);
DISPLAY 0.978723 (2275 -1400);
PAINT WHITE (2275 -1400);
DISPLAY INVISIBLE (2275 -1400);
FORCEPROP 0 LAST $SEC 1
J 0
(2275 -1425);
DISPLAY INVISIBLE (2275 -1425);
FORCEPROP 0 LAST CDS_SEC 1
J 0
(2275 -1425);
DISPLAY INVISIBLE (2275 -1425);
FORCEPROP 1 LASTPIN (2225 -1450) $PN 1
J 0
(2235 -1470);
DISPLAY 0.787234 (2235 -1470);
PAINT MONO (2235 -1470);
DISPLAY INVISIBLE (2235 -1470);
FORCEPROP 1 LASTPIN (2225 -1650) $PN 2
J 0
(2235 -1670);
DISPLAY 0.787234 (2235 -1670);
PAINT MONO (2235 -1670);
DISPLAY INVISIBLE (2235 -1670);
FORCEADD UNIVERSAL_POWER..1
R 2
(2225 -900);
FORCEPROP 3 LASTPIN (2225 -950) SIG_NAME P3V3_E1S_0_R\g
J 0
(2235 -940);
DISPLAY 0.659574 (2235 -940);
PAINT MONO (2235 -940);
DISPLAY INVISIBLE (2235 -940);
FORCEPROP 1 LAST HDL_POWER P3V3_E1S_0_R
J 1
(2225 -850);
DISPLAY 0.510638 (2225 -850);
PAINT GREEN (2225 -850);
FORCEPROP 2 LAST CDS_LIB logical_power
J 0
(2225 -900);
DISPLAY INVISIBLE (2225 -900);
FORCEPROP 1 LAST PATH I35
J 2
(2175 -875);
DISPLAY 0.872340 (2175 -875);
PAINT AQUA (2175 -875);
DISPLAY INVISIBLE (2175 -875);
FORCEADD GND..1
(-2200 375);
FORCEPROP 3 LASTPIN (-2200 425) SIG_NAME GND\g
J 0
(-2190 435);
DISPLAY 0.659574 (-2190 435);
PAINT MONO (-2190 435);
DISPLAY INVISIBLE (-2190 435);
FORCEPROP 1 LAST HDL_POWER GND
J 0
(-2200 525);
DISPLAY 0.872340 (-2200 525);
PAINT GREEN (-2200 525);
DISPLAY INVISIBLE (-2200 525);
FORCEPROP 2 LAST CDS_LIB logical_power
J 0
(-2200 375);
DISPLAY INVISIBLE (-2200 375);
FORCEPROP 1 LAST SIZE 1B
J 0
(-2125 325);
DISPLAY 0.872340 (-2125 325);
PAINT GREEN (-2125 325);
DISPLAY INVISIBLE (-2125 325);
FORCEPROP 1 LAST PATH I36
J 0
(-2125 375);
DISPLAY 0.872340 (-2125 375);
PAINT AQUA (-2125 375);
DISPLAY INVISIBLE (-2125 375);
FORCEADD Q_CAP..1
(-2200 725);
FORCEPROP 1 LAST PART_NUMBER CH4223K1B00
J 0
(-2150 675);
DISPLAY 0.510638 (-2150 675);
DISPLAY INVISIBLE (-2150 675);
FORCEPROP 2 LAST ROOM E1S1_P12V_MPS_MAM_BOM3
J 0
(-2150 825);
DISPLAY 0.510638 (-2150 825);
FORCEPROP 1 LAST VALUE 0.22UF
J 0
(-2150 750);
DISPLAY 0.510638 (-2150 750);
FORCEPROP 1 LAST PACK_TYPE 0402
J 0
(-2150 650);
DISPLAY 0.510638 (-2150 650);
FORCEPROP 1 LAST MATERIAL X7R
J 0
(-2150 700);
DISPLAY 0.510638 (-2150 700);
FORCEPROP 1 LAST VOLTAGE 16V
J 0
(-2150 725);
DISPLAY 0.510638 (-2150 725);
FORCEPROP 1 LAST LOCATION PC2196
J 0
(-2150 775);
DISPLAY 0.510638 (-2150 775);
FORCEPROP 1 LAST TOLERANCE 10%
J 0
(-2150 675);
DISPLAY 0.638298 (-2150 675);
DISPLAY INVISIBLE (-2150 675);
FORCEPROP 2 LAST CDS_LIB pure_quanta
J 0
(-2200 725);
DISPLAY INVISIBLE (-2200 725);
FORCEPROP 2 LAST ROOM1 E1S1_P12V_MPS_TIC_BOM4
J 0
(-2150 875);
DISPLAY 1.021277 (-2150 875);
DISPLAY INVISIBLE (-2150 875);
FORCEPROP 1 LAST PATH I37
J 0
(-2150 875);
DISPLAY 0.978723 (-2150 875);
PAINT WHITE (-2150 875);
DISPLAY INVISIBLE (-2150 875);
FORCEPROP 0 LAST $SEC 1
J 0
(-2150 875);
DISPLAY INVISIBLE (-2150 875);
FORCEPROP 0 LAST CDS_SEC 1
J 0
(-2150 875);
DISPLAY INVISIBLE (-2150 875);
FORCEPROP 1 LASTPIN (-2200 825) $PN 1
J 0
(-2190 805);
DISPLAY 0.787234 (-2190 805);
PAINT MONO (-2190 805);
DISPLAY INVISIBLE (-2190 805);
FORCEPROP 1 LASTPIN (-2200 625) $PN 2
J 0
(-2190 605);
DISPLAY 0.787234 (-2190 605);
PAINT MONO (-2190 605);
DISPLAY INVISIBLE (-2190 605);
FORCEADD OFFPAGE..1
(-2250 1175);
PAINT AQUA (-2250 1175);
FORCEPROP 2 LAST $XR2 193 
J 0
(-2742 1175);
DISPLAY 0.638298 (-2742 1175);
PAINT MONO (-2742 1175);
FORCEPROP 2 LAST $XR1 192 
J 0
(-2622 1175);
DISPLAY 0.638298 (-2622 1175);
PAINT MONO (-2622 1175);
FORCEPROP 2 LAST $XR0 191 
J 0
(-2502 1175);
DISPLAY 0.638298 (-2502 1175);
PAINT MONO (-2502 1175);
FORCEPROP 1 LAST COMMENT_BODY TRUE
J 0
(-2125 1075);
DISPLAY 0.872340 (-2125 1075);
PAINT GREEN (-2125 1075);
DISPLAY INVISIBLE (-2125 1075);
FORCEPROP 1 LAST OFFPAGE TRUE
J 0
(-1925 1050);
DISPLAY 0.872340 (-1925 1050);
PAINT AQUA (-1925 1050);
DISPLAY INVISIBLE (-1925 1050);
FORCEPROP 2 LAST CDS_LIB standard
J 0
(-2250 1175);
DISPLAY INVISIBLE (-2250 1175);
FORCEPROP 2 LAST PATH I38
J 0
(-2600 1225);
DISPLAY 1.021277 (-2600 1225);
DISPLAY INVISIBLE (-2600 1225);
FORCEADD GND..1
(-1775 300);
FORCEPROP 3 LASTPIN (-1775 350) SIG_NAME GND\g
J 0
(-1765 360);
DISPLAY 0.659574 (-1765 360);
PAINT MONO (-1765 360);
DISPLAY INVISIBLE (-1765 360);
FORCEPROP 1 LAST HDL_POWER GND
J 0
(-1775 450);
DISPLAY 0.872340 (-1775 450);
PAINT GREEN (-1775 450);
DISPLAY INVISIBLE (-1775 450);
FORCEPROP 2 LAST CDS_LIB logical_power
J 0
(-1775 300);
DISPLAY INVISIBLE (-1775 300);
FORCEPROP 1 LAST SIZE 1B
J 0
(-1700 250);
DISPLAY 0.872340 (-1700 250);
PAINT GREEN (-1700 250);
DISPLAY INVISIBLE (-1700 250);
FORCEPROP 1 LAST PATH I39
J 0
(-1700 300);
DISPLAY 0.872340 (-1700 300);
PAINT AQUA (-1700 300);
DISPLAY INVISIBLE (-1700 300);
FORCEADD Q_RES..2
(-750 -1625);
FORCEPROP 1 LAST PART_NUMBER CS37152FB05
J 0
(-700 -1700);
DISPLAY 0.510638 (-700 -1700);
DISPLAY INVISIBLE (-700 -1700);
FORCEPROP 1 LAST TOLERANCE 1%
J 0
(-700 -1650);
DISPLAY 0.510638 (-700 -1650);
FORCEPROP 1 LAST VALUE 71.5K
J 0
(-700 -1625);
DISPLAY 0.510638 (-700 -1625);
FORCEPROP 1 LAST MATERIAL EMPTY
J 0
(-700 -1675);
DISPLAY 0.510638 (-700 -1675);
PAINT RED (-700 -1675);
FORCEPROP 1 LAST PACK_TYPE 0402LF
J 0
(-700 -1725);
DISPLAY 0.510638 (-700 -1725);
FORCEPROP 2 LAST ROOM E1S1_P3V3_BOM2
J 0
(-700 -1550);
DISPLAY 0.510638 (-700 -1550);
FORCEPROP 1 LAST LOCATION PR3945
J 0
(-700 -1600);
DISPLAY 0.510638 (-700 -1600);
FORCEPROP 2 LAST CDS_LIB pure_quanta
J 0
(-750 -1625);
DISPLAY INVISIBLE (-750 -1625);
FORCEPROP 1 LAST WATTAGE 1/16W
J 0
(-725 -1650);
DISPLAY 0.723404 (-725 -1650);
PAINT SKYBLUE (-725 -1650);
DISPLAY INVISIBLE (-725 -1650);
FORCEPROP 1 LAST PATH I4
J 0
(-700 -1450);
DISPLAY 0.978723 (-700 -1450);
PAINT WHITE (-700 -1450);
DISPLAY INVISIBLE (-700 -1450);
FORCEPROP 0 LAST $SEC 1
J 0
(-725 -1500);
DISPLAY INVISIBLE (-725 -1500);
FORCEPROP 0 LAST CDS_SEC 1
J 0
(-725 -1500);
DISPLAY INVISIBLE (-725 -1500);
FORCEPROP 1 LASTPIN (-750 -1525) $PN 1
J 0
(-745 -1563);
DISPLAY 0.787234 (-745 -1563);
PAINT MONO (-745 -1563);
DISPLAY INVISIBLE (-745 -1563);
FORCEPROP 1 LASTPIN (-750 -1725) $PN 2
J 0
(-745 -1715);
DISPLAY 0.787234 (-745 -1715);
PAINT MONO (-745 -1715);
DISPLAY INVISIBLE (-745 -1715);
FORCEADD Q_RES..2
(-1775 600);
FORCEPROP 1 LAST PART_NUMBER CS34642FB02
J 0
(-1725 525);
DISPLAY 0.510638 (-1725 525);
DISPLAY INVISIBLE (-1725 525);
FORCEPROP 1 LAST VALUE 46.4K
J 0
(-1725 625);
DISPLAY 0.510638 (-1725 625);
FORCEPROP 1 LAST PACK_TYPE 0402LF
J 0
(-1725 500);
DISPLAY 0.510638 (-1725 500);
FORCEPROP 1 LAST TOLERANCE 1%
J 0
(-1725 600);
DISPLAY 0.510638 (-1725 600);
FORCEPROP 1 LAST WATTAGE 1/16W
J 0
(-1725 575);
DISPLAY 0.510638 (-1725 575);
FORCEPROP 1 LAST MATERIAL CHIP
J 0
(-1725 550);
DISPLAY 0.510638 (-1725 550);
FORCEPROP 2 LAST ROOM E1S1_P12V_MPS_MAM_BOM3
J 0
(-1725 475);
DISPLAY 0.510638 (-1725 475);
FORCEPROP 1 LAST LOCATION PR3944
J 0
(-1725 650);
DISPLAY 0.510638 (-1725 650);
FORCEPROP 1 LASTPIN (-1775 700) $PN 1
J 0
(-1770 662);
DISPLAY 0.510638 (-1770 662);
PAINT MONO (-1770 662);
FORCEPROP 1 LASTPIN (-1775 500) $PN 2
J 0
(-1770 510);
DISPLAY 0.510638 (-1770 510);
PAINT MONO (-1770 510);
FORCEPROP 2 LAST CDS_LIB pure_quanta
J 0
(-1775 600);
DISPLAY INVISIBLE (-1775 600);
FORCEPROP 2 LAST ROOM1 E1S1_P12V_MPS_TIC_BOM4
J 0
(-1725 750);
DISPLAY 1.021277 (-1725 750);
DISPLAY INVISIBLE (-1725 750);
FORCEPROP 1 LAST PATH I40
J 0
(-1725 775);
DISPLAY 0.978723 (-1725 775);
PAINT WHITE (-1725 775);
DISPLAY INVISIBLE (-1725 775);
FORCEPROP 0 LAST $SEC 1
J 0
(-1725 750);
DISPLAY 0.680851 (-1725 750);
PAINT MONO (-1725 750);
DISPLAY INVISIBLE (-1725 750);
FORCEPROP 0 LAST CDS_SEC 1
J 0
(-1725 725);
DISPLAY INVISIBLE (-1725 725);
FORCEADD GND..1
(-1425 50);
FORCEPROP 3 LASTPIN (-1425 100) SIG_NAME GND\g
J 0
(-1415 110);
DISPLAY 0.659574 (-1415 110);
PAINT MONO (-1415 110);
DISPLAY INVISIBLE (-1415 110);
FORCEPROP 1 LAST HDL_POWER GND
J 0
(-1425 200);
DISPLAY 0.872340 (-1425 200);
PAINT GREEN (-1425 200);
DISPLAY INVISIBLE (-1425 200);
FORCEPROP 2 LAST CDS_LIB logical_power
J 0
(-1425 50);
DISPLAY INVISIBLE (-1425 50);
FORCEPROP 1 LAST SIZE 1B
J 0
(-1350 0);
DISPLAY 0.872340 (-1350 0);
PAINT GREEN (-1350 0);
DISPLAY INVISIBLE (-1350 0);
FORCEPROP 1 LAST PATH I41
J 0
(-1350 50);
DISPLAY 0.872340 (-1350 50);
PAINT AQUA (-1350 50);
DISPLAY INVISIBLE (-1350 50);
FORCEADD Q_CAP..1
(-1425 275);
FORCEPROP 1 LAST PART_NUMBER CH1566K1B09
J 0
(-1375 225);
DISPLAY 0.510638 (-1375 225);
DISPLAY INVISIBLE (-1375 225);
FORCEPROP 1 LAST PACK_TYPE C0402
J 0
(-1375 200);
DISPLAY 0.510638 (-1375 200);
FORCEPROP 1 LAST MATERIAL X7R
J 0
(-1375 250);
DISPLAY 0.510638 (-1375 250);
FORCEPROP 1 LAST VOLTAGE 50V
J 0
(-1375 275);
DISPLAY 0.510638 (-1375 275);
FORCEPROP 1 LAST VALUE 560PF
J 0
(-1375 300);
DISPLAY 0.510638 (-1375 300);
FORCEPROP 2 LAST ROOM E1S1_P12V_MPS_MAM_BOM3
J 0
(-1375 175);
DISPLAY 0.510638 (-1375 175);
FORCEPROP 1 LAST LOCATION PC2341
J 0
(-1375 325);
DISPLAY 0.510638 (-1375 325);
FORCEPROP 1 LASTPIN (-1425 375) $PN 1
J 0
(-1415 355);
DISPLAY 0.510638 (-1415 355);
PAINT MONO (-1415 355);
FORCEPROP 1 LASTPIN (-1425 175) $PN 2
J 0
(-1415 155);
DISPLAY 0.510638 (-1415 155);
PAINT MONO (-1415 155);
FORCEPROP 1 LAST TOLERANCE 10%
J 0
(-1375 225);
DISPLAY 0.638298 (-1375 225);
DISPLAY INVISIBLE (-1375 225);
FORCEPROP 2 LAST CDS_LIB pure_quanta
J 0
(-1425 275);
DISPLAY INVISIBLE (-1425 275);
FORCEPROP 2 LAST ROOM1 E1S1_P12V_MPS_TIC_BOM4
J 0
(-1375 425);
DISPLAY 1.021277 (-1375 425);
DISPLAY INVISIBLE (-1375 425);
FORCEPROP 1 LAST PATH I42
J 0
(-1375 425);
DISPLAY 0.978723 (-1375 425);
PAINT WHITE (-1375 425);
DISPLAY INVISIBLE (-1375 425);
FORCEPROP 0 LAST $SEC 1
J 0
(-1375 375);
DISPLAY 0.680851 (-1375 375);
PAINT MONO (-1375 375);
DISPLAY INVISIBLE (-1375 375);
FORCEPROP 0 LAST CDS_SEC 1
J 0
(-1375 375);
DISPLAY 1.021277 (-1375 375);
DISPLAY INVISIBLE (-1375 375);
FORCEADD Q_RES..2
(-1425 600);
FORCEPROP 1 LAST PART_NUMBER CS32002FB06
J 0
(-1375 525);
DISPLAY 0.510638 (-1375 525);
DISPLAY INVISIBLE (-1375 525);
FORCEPROP 1 LAST WATTAGE 1/16W
J 0
(-1375 575);
DISPLAY 0.510638 (-1375 575);
FORCEPROP 1 LAST MATERIAL CHIP
J 0
(-1375 550);
DISPLAY 0.510638 (-1375 550);
FORCEPROP 1 LAST TOLERANCE 1%
J 0
(-1375 600);
DISPLAY 0.510638 (-1375 600);
FORCEPROP 1 LAST VALUE 20K
J 0
(-1375 625);
DISPLAY 0.510638 (-1375 625);
FORCEPROP 1 LAST PACK_TYPE 0402LF
J 0
(-1375 500);
DISPLAY 0.510638 (-1375 500);
FORCEPROP 2 LAST ROOM E1S1_P12V_MPS_MAM_BOM3
J 0
(-1375 700);
DISPLAY 0.510638 (-1375 700);
FORCEPROP 1 LAST LOCATION PR4541
J 0
(-1375 650);
DISPLAY 0.510638 (-1375 650);
FORCEPROP 1 LASTPIN (-1425 700) $PN 1
J 0
(-1420 662);
DISPLAY 0.510638 (-1420 662);
PAINT MONO (-1420 662);
FORCEPROP 1 LASTPIN (-1425 500) $PN 2
J 0
(-1420 510);
DISPLAY 0.510638 (-1420 510);
PAINT MONO (-1420 510);
FORCEPROP 2 LAST CDS_LIB pure_quanta
J 0
(-1425 600);
DISPLAY INVISIBLE (-1425 600);
FORCEPROP 2 LAST ROOM1 E1S1_P12V_MPS_TIC_BOM4
J 0
(-1375 750);
DISPLAY 1.021277 (-1375 750);
DISPLAY INVISIBLE (-1375 750);
FORCEPROP 1 LAST PATH I43
J 0
(-1375 775);
DISPLAY 0.978723 (-1375 775);
PAINT WHITE (-1375 775);
DISPLAY INVISIBLE (-1375 775);
FORCEPROP 0 LAST $SEC 1
J 0
(-1375 700);
DISPLAY 0.680851 (-1375 700);
PAINT MONO (-1375 700);
DISPLAY INVISIBLE (-1375 700);
FORCEPROP 0 LAST CDS_SEC 1
J 0
(-1375 700);
DISPLAY 1.021277 (-1375 700);
DISPLAY INVISIBLE (-1375 700);
FORCEADD GND..1
(-1300 925);
FORCEPROP 3 LASTPIN (-1300 975) SIG_NAME GND\g
J 0
(-1290 985);
DISPLAY 0.659574 (-1290 985);
PAINT MONO (-1290 985);
DISPLAY INVISIBLE (-1290 985);
FORCEPROP 1 LAST HDL_POWER GND
J 0
(-1300 1075);
DISPLAY 0.872340 (-1300 1075);
PAINT GREEN (-1300 1075);
DISPLAY INVISIBLE (-1300 1075);
FORCEPROP 1 LAST SIZE 1B
J 0
(-1225 875);
DISPLAY 0.872340 (-1225 875);
PAINT GREEN (-1225 875);
DISPLAY INVISIBLE (-1225 875);
FORCEPROP 2 LAST CDS_LIB logical_power
J 0
(-1300 925);
DISPLAY INVISIBLE (-1300 925);
FORCEPROP 1 LAST PATH I44
J 0
(-1225 925);
DISPLAY 0.872340 (-1225 925);
PAINT AQUA (-1225 925);
DISPLAY INVISIBLE (-1225 925);
FORCEADD Q_RES..1
(-1425 1175);
FORCEPROP 1 LAST PART_NUMBER CS00002JB13
J 0
(-1500 1125);
DISPLAY 0.510638 (-1500 1125);
DISPLAY INVISIBLE (-1500 1125);
FORCEPROP 1 LAST MATERIAL CHIP
J 0
(-1500 1100);
DISPLAY 0.510638 (-1500 1100);
FORCEPROP 1 LAST WATTAGE 1/16W
J 2
(-1225 1100);
DISPLAY 0.510638 (-1225 1100);
FORCEPROP 1 LAST TOLERANCE 5%
J 0
(-1250 1175);
DISPLAY 0.510638 (-1250 1175);
FORCEPROP 1 LAST VALUE 0
J 2
(-1275 1175);
DISPLAY 0.510638 (-1275 1175);
FORCEPROP 1 LAST PACK_TYPE 0402LF
J 0
(-1175 1175);
DISPLAY 0.510638 (-1175 1175);
FORCEPROP 2 LAST ROOM E1S1_P12V_MPS_MAM_BOM3
J 0
(-1475 1275);
DISPLAY 0.510638 (-1475 1275);
FORCEPROP 1 LAST $LOCATION R3943
J 0
(-1475 1225);
DISPLAY 0.510638 (-1475 1225);
FORCEPROP 1 LASTPIN (-1525 1175) $PN 1
J 0
(-1513 1187);
DISPLAY 0.510638 (-1513 1187);
PAINT MONO (-1513 1187);
FORCEPROP 1 LASTPIN (-1325 1175) $PN 2
J 0
(-1363 1187);
DISPLAY 0.510638 (-1363 1187);
PAINT MONO (-1363 1187);
FORCEPROP 2 LAST CDS_LIB pure_quanta
J 0
(-1425 1175);
DISPLAY INVISIBLE (-1425 1175);
FORCEPROP 2 LAST ROOM1 E1S1_P12V_MPS_TIC_BOM4
J 0
(-1475 1325);
DISPLAY 1.021277 (-1475 1325);
DISPLAY INVISIBLE (-1475 1325);
FORCEPROP 1 LAST PATH I45
J 0
(-1475 1325);
DISPLAY 0.978723 (-1475 1325);
PAINT WHITE (-1475 1325);
DISPLAY INVISIBLE (-1475 1325);
FORCEPROP 0 LAST CDS_LOCATION R3943
J 0
(-1475 1275);
DISPLAY 1.021277 (-1475 1275);
DISPLAY INVISIBLE (-1475 1275);
FORCEPROP 0 LAST $SEC 1
J 0
(-1475 1275);
DISPLAY 0.680851 (-1475 1275);
PAINT MONO (-1475 1275);
DISPLAY INVISIBLE (-1475 1275);
FORCEPROP 0 LAST CDS_SEC 1
J 0
(-1475 1275);
DISPLAY 1.021277 (-1475 1275);
DISPLAY INVISIBLE (-1475 1275);
FORCEADD GND..1
(-900 275);
FORCEPROP 3 LASTPIN (-900 325) SIG_NAME GND\g
J 0
(-890 335);
DISPLAY 0.659574 (-890 335);
PAINT MONO (-890 335);
DISPLAY INVISIBLE (-890 335);
FORCEPROP 1 LAST HDL_POWER GND
J 0
(-900 425);
DISPLAY 0.872340 (-900 425);
PAINT GREEN (-900 425);
DISPLAY INVISIBLE (-900 425);
FORCEPROP 1 LAST SIZE 1B
J 0
(-825 225);
DISPLAY 0.872340 (-825 225);
PAINT GREEN (-825 225);
DISPLAY INVISIBLE (-825 225);
FORCEPROP 2 LAST CDS_LIB logical_power
J 0
(-900 275);
DISPLAY INVISIBLE (-900 275);
FORCEPROP 1 LAST PATH I46
J 0
(-825 275);
DISPLAY 0.872340 (-825 275);
PAINT AQUA (-825 275);
DISPLAY INVISIBLE (-825 275);
FORCEADD Q_CAP..1
(-900 500);
FORCEPROP 1 LAST PART_NUMBER CH3474K1B04
J 0
(-850 450);
DISPLAY 0.510638 (-850 450);
DISPLAY INVISIBLE (-850 450);
FORCEPROP 1 LAST MATERIAL X7R
J 0
(-850 475);
DISPLAY 0.510638 (-850 475);
FORCEPROP 1 LAST PACK_TYPE C0402
J 0
(-850 425);
DISPLAY 0.510638 (-850 425);
FORCEPROP 1 LAST VOLTAGE 25V
J 0
(-850 500);
DISPLAY 0.510638 (-850 500);
FORCEPROP 2 LAST ROOM E1S1_P12V_MPS_MAM_BOM3
J 0
(-850 600);
DISPLAY 0.404255 (-850 600);
FORCEPROP 1 LAST VALUE 0.047UF
J 0
(-850 525);
DISPLAY 0.510638 (-850 525);
FORCEPROP 1 LAST LOCATION PC2281
J 0
(-850 550);
DISPLAY 0.510638 (-850 550);
FORCEPROP 1 LAST TOLERANCE 10%
J 0
(-850 450);
DISPLAY 0.638298 (-850 450);
DISPLAY INVISIBLE (-850 450);
FORCEPROP 2 LAST CDS_LIB pure_quanta
J 0
(-900 500);
DISPLAY INVISIBLE (-900 500);
FORCEPROP 2 LAST ROOM1 E1S1_P12V_MPS_TIC_BOM4
J 0
(-850 650);
DISPLAY 1.021277 (-850 650);
DISPLAY INVISIBLE (-850 650);
FORCEPROP 1 LAST PATH I47
J 0
(-850 650);
DISPLAY 0.978723 (-850 650);
PAINT WHITE (-850 650);
DISPLAY INVISIBLE (-850 650);
FORCEPROP 0 LAST $SEC 1
J 0
(-850 650);
DISPLAY INVISIBLE (-850 650);
FORCEPROP 0 LAST CDS_SEC 1
J 0
(-850 650);
DISPLAY INVISIBLE (-850 650);
FORCEPROP 1 LASTPIN (-900 600) $PN 1
J 0
(-890 580);
DISPLAY 0.787234 (-890 580);
PAINT MONO (-890 580);
DISPLAY INVISIBLE (-890 580);
FORCEPROP 1 LASTPIN (-900 400) $PN 2
J 0
(-890 380);
DISPLAY 0.787234 (-890 380);
PAINT MONO (-890 380);
DISPLAY INVISIBLE (-890 380);
FORCEADD GND..1
(-559 441);
FORCEPROP 3 LASTPIN (-559 491) SIG_NAME GND\g
J 0
(-549 501);
DISPLAY 0.659574 (-549 501);
PAINT MONO (-549 501);
DISPLAY INVISIBLE (-549 501);
FORCEPROP 1 LAST HDL_POWER GND
J 0
(-559 591);
DISPLAY 0.872340 (-559 591);
PAINT GREEN (-559 591);
DISPLAY INVISIBLE (-559 591);
FORCEPROP 1 LAST SIZE 1B
J 0
(-484 391);
DISPLAY 0.872340 (-484 391);
PAINT GREEN (-484 391);
DISPLAY INVISIBLE (-484 391);
FORCEPROP 2 LAST CDS_LIB logical_power
J 0
(-559 441);
DISPLAY INVISIBLE (-559 441);
FORCEPROP 1 LAST PATH I48
J 0
(-484 441);
DISPLAY 0.872340 (-484 441);
PAINT AQUA (-484 441);
DISPLAY INVISIBLE (-484 441);
FORCEADD RS31312R..1
(-100 1050);
FORCEPROP 1 LAST PART_NUMBER AL031312000
J 0
(-347 1714);
DISPLAY 0.723404 (-347 1714);
PAINT GREEN (-347 1714);
DISPLAY INVISIBLE (-347 1714);
FORCEPROP 2 LAST ROOM E1S1_P12V_MPS_MAM_BOM3
J 0
(-350 1775);
DISPLAY 0.510638 (-350 1775);
FORCEPROP 2 LAST VALUE RS31312R
J 0
(-350 1650);
DISPLAY 0.510638 (-350 1650);
FORCEPROP 1 LAST MATERIAL IC
J 0
(-347 1587);
DISPLAY 0.723404 (-347 1587);
PAINT GREEN (-347 1587);
FORCEPROP 1 LAST LOCATION PU292
J 0
(-347 1861);
DISPLAY 0.723404 (-347 1861);
PAINT GREEN (-347 1861);
FORCEPROP 0 LASTPIN (300 925) $PN 12
J 0
(310 935);
DISPLAY 0.680851 (310 935);
PAINT MONO (310 935);
FORCEPROP 0 LASTPIN (-500 1175) $PN 1
J 2
(-510 1185);
DISPLAY 0.680851 (-510 1185);
PAINT MONO (-510 1185);
FORCEPROP 0 LASTPIN (-500 975) $PN 3
J 2
(-510 985);
DISPLAY 0.680851 (-510 985);
PAINT MONO (-510 985);
FORCEPROP 0 LASTPIN (300 675) $PN 9
J 0
(310 685);
DISPLAY 0.680851 (310 685);
PAINT MONO (310 685);
FORCEPROP 0 LASTPIN (-500 575) $PN 7
J 2
(-510 585);
DISPLAY 0.680851 (-510 585);
PAINT MONO (-510 585);
FORCEPROP 0 LASTPIN (300 575) $PN 8
J 0
(310 585);
DISPLAY 0.680851 (310 585);
PAINT MONO (310 585);
FORCEPROP 0 LASTPIN (-500 775) $PN 5
J 2
(-510 785);
DISPLAY 0.680851 (-510 785);
PAINT MONO (-510 785);
FORCEPROP 0 LASTPIN (-500 1075) $PN 2
J 2
(-510 1085);
DISPLAY 0.680851 (-510 1085);
PAINT MONO (-510 1085);
FORCEPROP 0 LASTPIN (300 825) $PN 11
J 0
(310 835);
DISPLAY 0.680851 (310 835);
PAINT MONO (310 835);
FORCEPROP 0 LASTPIN (300 1525) $PN 10
J 0
(310 1535);
DISPLAY 0.680851 (310 1535);
PAINT MONO (310 1535);
FORCEPROP 0 LASTPIN (-500 675) $PN 6
J 2
(-510 685);
DISPLAY 0.680851 (-510 685);
PAINT MONO (-510 685);
FORCEPROP 0 LASTPIN (-500 875) $PN 4
J 2
(-510 885);
DISPLAY 0.680851 (-510 885);
PAINT MONO (-510 885);
FORCEPROP 0 LASTPIN (-500 1525) $PN 21_22
J 2
(-510 1535);
DISPLAY 0.680851 (-510 1535);
PAINT MONO (-510 1535);
FORCEPROP 0 LASTPIN (-500 1475) $PN 23
J 2
(-510 1485);
DISPLAY 0.680851 (-510 1485);
PAINT MONO (-510 1485);
FORCEPROP 0 LASTPIN (-500 1425) $PN 24
J 2
(-510 1435);
DISPLAY 0.680851 (-510 1435);
PAINT MONO (-510 1435);
FORCEPROP 0 LASTPIN (-500 1375) $PN 25
J 2
(-510 1385);
DISPLAY 0.680851 (-510 1385);
PAINT MONO (-510 1385);
FORCEPROP 0 LASTPIN (-500 1325) $PN 26
J 2
(-510 1335);
DISPLAY 0.680851 (-510 1335);
PAINT MONO (-510 1335);
FORCEPROP 0 LASTPIN (300 1025) $PN 13
J 0
(310 1035);
DISPLAY 0.680851 (310 1035);
PAINT MONO (310 1035);
FORCEPROP 0 LASTPIN (300 1075) $PN 14
J 0
(310 1085);
DISPLAY 0.680851 (310 1085);
PAINT MONO (310 1085);
FORCEPROP 0 LASTPIN (300 1125) $PN 15
J 0
(310 1135);
DISPLAY 0.680851 (310 1135);
PAINT MONO (310 1135);
FORCEPROP 0 LASTPIN (300 1175) $PN 16
J 0
(310 1185);
DISPLAY 0.680851 (310 1185);
PAINT MONO (310 1185);
FORCEPROP 0 LASTPIN (300 1225) $PN 17
J 0
(310 1235);
DISPLAY 0.680851 (310 1235);
PAINT MONO (310 1235);
FORCEPROP 0 LASTPIN (300 1275) $PN 18
J 0
(310 1285);
DISPLAY 0.680851 (310 1285);
PAINT MONO (310 1285);
FORCEPROP 0 LASTPIN (300 1325) $PN 19
J 0
(310 1335);
DISPLAY 0.680851 (310 1335);
PAINT MONO (310 1335);
FORCEPROP 0 LASTPIN (300 1375) $PN 20
J 0
(310 1385);
DISPLAY 0.680851 (310 1385);
PAINT MONO (310 1385);
FORCEPROP 0 LAST PART_TYPE SMLF
J 0
(-353 1835);
DISPLAY 1.021277 (-353 1835);
DISPLAY INVISIBLE (-353 1835);
FORCEPROP 2 LAST CDS_LIB pure_quanta
J 0
(-100 1050);
DISPLAY INVISIBLE (-100 1050);
FORCEPROP 1 LAST NEEDS_NO_SIZE TRUE
J 0
(-100 1050);
DISPLAY 0.723404 (-100 1050);
PAINT GREEN (-100 1050);
DISPLAY INVISIBLE (-100 1050);
FORCEPROP 1 LAST CDS_LMAN_SYM_OUTLINE -250,525,250,-525
J 0
(-100 1050);
DISPLAY 0.468085 (-100 1050);
PAINT GREEN (-100 1050);
DISPLAY INVISIBLE (-100 1050);
FORCEPROP 2 LAST ROOM1 E1S1_P12V_MPS_TIC_BOM4
J 0
(-325 1950);
DISPLAY 1.021277 (-325 1950);
DISPLAY INVISIBLE (-325 1950);
FORCEPROP 1 LAST PATH I49
J 0
(-100 1050);
DISPLAY 0.723404 (-100 1050);
PAINT GREEN (-100 1050);
DISPLAY INVISIBLE (-100 1050);
FORCEPROP 0 LAST $SEC 1
J 0
(-325 1900);
DISPLAY 0.680851 (-325 1900);
PAINT MONO (-325 1900);
DISPLAY INVISIBLE (-325 1900);
FORCEPROP 0 LAST CDS_SEC 1
J 0
(-275 1625);
DISPLAY INVISIBLE (-275 1625);
FORCEADD Q_RES..1
(-675 -1325);
FORCEPROP 1 LAST PART_NUMBER CS00002JB13
J 0
(-750 -1375);
DISPLAY 0.510638 (-750 -1375);
DISPLAY INVISIBLE (-750 -1375);
FORCEPROP 1 LAST MATERIAL EMPTY
J 0
(-750 -1400);
DISPLAY 0.510638 (-750 -1400);
PAINT RED (-750 -1400);
FORCEPROP 1 LAST VALUE 0
J 2
(-525 -1325);
DISPLAY 0.510638 (-525 -1325);
FORCEPROP 2 LAST ROOM E1S1_P3V3_BOM2
J 0
(-900 -1275);
DISPLAY 0.510638 (-900 -1275);
FORCEPROP 1 LAST WATTAGE 1/16W
J 2
(-500 -1400);
DISPLAY 0.510638 (-500 -1400);
FORCEPROP 1 LAST PACK_TYPE 0402LF
J 0
(-425 -1325);
DISPLAY 0.510638 (-425 -1325);
FORCEPROP 1 LAST TOLERANCE 5%
J 0
(-500 -1325);
DISPLAY 0.510638 (-500 -1325);
FORCEPROP 1 LAST $LOCATION R3946
J 0
(-900 -1325);
DISPLAY 0.510638 (-900 -1325);
FORCEPROP 1 LASTPIN (-775 -1325) $PN 1
J 0
(-763 -1313);
DISPLAY 0.510638 (-763 -1313);
PAINT MONO (-763 -1313);
FORCEPROP 1 LASTPIN (-575 -1325) $PN 2
J 0
(-613 -1313);
DISPLAY 0.510638 (-613 -1313);
PAINT MONO (-613 -1313);
FORCEPROP 2 LAST CDS_LIB pure_quanta
J 0
(-675 -1325);
DISPLAY INVISIBLE (-675 -1325);
FORCEPROP 1 LAST PATH I5
J 0
(-725 -1175);
DISPLAY 0.978723 (-725 -1175);
PAINT WHITE (-725 -1175);
DISPLAY INVISIBLE (-725 -1175);
FORCEPROP 0 LAST CDS_LOCATION R3946
J 0
(-900 -1275);
DISPLAY 1.021277 (-900 -1275);
DISPLAY INVISIBLE (-900 -1275);
FORCEPROP 0 LAST $SEC 1
J 0
(-900 -1275);
DISPLAY 0.680851 (-900 -1275);
PAINT MONO (-900 -1275);
DISPLAY INVISIBLE (-900 -1275);
FORCEPROP 0 LAST CDS_SEC 1
J 0
(-900 -1275);
DISPLAY 1.021277 (-900 -1275);
DISPLAY INVISIBLE (-900 -1275);
FORCEADD GND..1
(-975 1350);
FORCEPROP 3 LASTPIN (-975 1400) SIG_NAME GND\g
J 0
(-965 1410);
DISPLAY 0.659574 (-965 1410);
PAINT MONO (-965 1410);
DISPLAY INVISIBLE (-965 1410);
FORCEPROP 1 LAST HDL_POWER GND
J 0
(-975 1500);
DISPLAY 0.872340 (-975 1500);
PAINT GREEN (-975 1500);
DISPLAY INVISIBLE (-975 1500);
FORCEPROP 2 LAST CDS_LIB logical_power
J 0
(-975 1350);
DISPLAY INVISIBLE (-975 1350);
FORCEPROP 1 LAST SIZE 1B
J 0
(-900 1300);
DISPLAY 0.872340 (-900 1300);
PAINT GREEN (-900 1300);
DISPLAY INVISIBLE (-900 1300);
FORCEPROP 1 LAST PATH I50
J 0
(-900 1350);
DISPLAY 0.872340 (-900 1350);
PAINT AQUA (-900 1350);
DISPLAY INVISIBLE (-900 1350);
FORCEADD Q_CAP..1
(-975 1575);
FORCEPROP 1 LAST PART_NUMBER CH5104KEB02
J 0
(-925 1525);
DISPLAY 0.510638 (-925 1525);
DISPLAY INVISIBLE (-925 1525);
FORCEPROP 2 LAST ROOM E1S1_P12V_MPS_MAM_BOM3
J 0
(-925 1675);
DISPLAY 0.510638 (-925 1675);
FORCEPROP 1 LAST VALUE 1UF
J 0
(-925 1600);
DISPLAY 0.510638 (-925 1600);
FORCEPROP 1 LAST MATERIAL X6S
J 0
(-925 1550);
DISPLAY 0.510638 (-925 1550);
FORCEPROP 1 LAST PACK_TYPE C0402
J 0
(-925 1500);
DISPLAY 0.510638 (-925 1500);
FORCEPROP 1 LAST VOLTAGE 25V
J 0
(-925 1575);
DISPLAY 0.510638 (-925 1575);
FORCEPROP 1 LAST LOCATION PC2198
J 0
(-925 1625);
DISPLAY 0.510638 (-925 1625);
FORCEPROP 1 LAST TOLERANCE 10%
J 0
(-925 1525);
DISPLAY 0.638298 (-925 1525);
DISPLAY INVISIBLE (-925 1525);
FORCEPROP 2 LAST CDS_LIB pure_quanta
J 0
(-975 1575);
DISPLAY INVISIBLE (-975 1575);
FORCEPROP 2 LAST ROOM1 E1S1_P12V_MPS_TIC_BOM4
J 0
(-925 1725);
DISPLAY 1.021277 (-925 1725);
DISPLAY INVISIBLE (-925 1725);
FORCEPROP 1 LAST PATH I51
J 0
(-925 1725);
DISPLAY 0.978723 (-925 1725);
PAINT WHITE (-925 1725);
DISPLAY INVISIBLE (-925 1725);
FORCEPROP 0 LAST $SEC 1
J 0
(-920 1717);
DISPLAY INVISIBLE (-920 1717);
FORCEPROP 0 LAST CDS_SEC 1
J 0
(-920 1717);
DISPLAY INVISIBLE (-920 1717);
FORCEPROP 1 LASTPIN (-975 1675) $PN 1
J 0
(-965 1655);
DISPLAY 0.787234 (-965 1655);
PAINT MONO (-965 1655);
DISPLAY INVISIBLE (-965 1655);
FORCEPROP 1 LASTPIN (-975 1475) $PN 2
J 0
(-965 1455);
DISPLAY 0.787234 (-965 1455);
PAINT MONO (-965 1455);
DISPLAY INVISIBLE (-965 1455);
FORCEADD UNIVERSAL_POWER..1
(-975 1925);
FORCEPROP 3 LASTPIN (-975 1875) SIG_NAME P12V_AUX\g
J 0
(-965 1885);
DISPLAY 0.659574 (-965 1885);
PAINT MONO (-965 1885);
DISPLAY INVISIBLE (-965 1885);
FORCEPROP 1 LAST HDL_POWER P12V_AUX
J 1
(-975 1975);
DISPLAY 0.510638 (-975 1975);
PAINT GREEN (-975 1975);
FORCEPROP 2 LAST CDS_LIB logical_power
J 0
(-975 1925);
DISPLAY INVISIBLE (-975 1925);
FORCEPROP 1 LAST PATH I52
J 0
(-925 1950);
DISPLAY 0.872340 (-925 1950);
PAINT AQUA (-925 1950);
DISPLAY INVISIBLE (-925 1950);
FORCEADD Q_RES..2
(525 300);
FORCEPROP 1 LAST PART_NUMBER CS35602FB00
J 0
(575 225);
DISPLAY 0.510638 (575 225);
DISPLAY INVISIBLE (575 225);
FORCEPROP 1 LAST PACK_TYPE 0402LF
J 0
(575 200);
DISPLAY 0.510638 (575 200);
FORCEPROP 1 LAST MATERIAL CHIP
J 0
(575 250);
DISPLAY 0.510638 (575 250);
FORCEPROP 1 LAST WATTAGE 1/16W
J 0
(575 275);
DISPLAY 0.510638 (575 275);
FORCEPROP 1 LAST TOLERANCE 1%
J 0
(575 300);
DISPLAY 0.510638 (575 300);
FORCEPROP 1 LAST VALUE 56K
J 0
(575 325);
DISPLAY 0.510638 (575 325);
FORCEPROP 2 LAST ROOM E1S1_P12V_MPS_MAM_BOM3
J 0
(575 400);
DISPLAY 0.404255 (575 400);
FORCEPROP 1 LAST LOCATION PR3949
J 0
(575 350);
DISPLAY 0.510638 (575 350);
FORCEPROP 1 LASTPIN (525 400) $PN 1
J 0
(530 362);
DISPLAY 0.510638 (530 362);
PAINT MONO (530 362);
FORCEPROP 1 LASTPIN (525 200) $PN 2
J 0
(530 210);
DISPLAY 0.510638 (530 210);
PAINT MONO (530 210);
FORCEPROP 2 LAST CDS_LIB pure_quanta
J 0
(525 300);
DISPLAY INVISIBLE (525 300);
FORCEPROP 2 LAST ROOM1 E1S1_P12V_MPS_TIC_BOM4
J 0
(575 450);
DISPLAY 1.021277 (575 450);
DISPLAY INVISIBLE (575 450);
FORCEPROP 1 LAST PATH I53
J 0
(575 475);
DISPLAY 0.978723 (575 475);
PAINT WHITE (575 475);
DISPLAY INVISIBLE (575 475);
FORCEPROP 0 LAST $SEC 1
J 0
(575 475);
DISPLAY 0.680851 (575 475);
PAINT MONO (575 475);
DISPLAY INVISIBLE (575 475);
FORCEPROP 0 LAST CDS_SEC 1
J 0
(575 475);
DISPLAY 1.021277 (575 475);
DISPLAY INVISIBLE (575 475);
FORCEADD Q_RES..1
(950 675);
FORCEPROP 1 LAST PART_NUMBER CS31002FB08
J 0
(800 725);
DISPLAY 0.510638 (800 725);
DISPLAY INVISIBLE (800 725);
FORCEPROP 1 LAST VALUE 10K
J 2
(900 625);
DISPLAY 0.510638 (900 625);
FORCEPROP 1 LAST TOLERANCE 1%
J 0
(1025 625);
DISPLAY 0.510638 (1025 625);
FORCEPROP 1 LAST WATTAGE 1/16W
J 2
(1325 625);
DISPLAY 0.510638 (1325 625);
FORCEPROP 1 LAST PACK_TYPE 0402LF
J 0
(1125 725);
DISPLAY 0.510638 (1125 725);
FORCEPROP 2 LAST ROOM E1S1_P12V_MPS_MAM_BOM3
J 0
(825 800);
DISPLAY 0.510638 (825 800);
FORCEPROP 1 LAST MATERIAL CHIP
J 0
(1100 625);
DISPLAY 0.510638 (1100 625);
FORCEPROP 1 LAST LOCATION PR3951
J 0
(825 750);
DISPLAY 0.510638 (825 750);
FORCEPROP 2 LAST CDS_LIB pure_quanta
J 0
(950 675);
DISPLAY INVISIBLE (950 675);
FORCEPROP 2 LAST ROOM1 E1S1_P12V_MPS_TIC_BOM4
J 0
(825 850);
DISPLAY 1.021277 (825 850);
DISPLAY INVISIBLE (825 850);
FORCEPROP 1 LAST PATH I54
J 0
(900 825);
DISPLAY 0.978723 (900 825);
PAINT WHITE (900 825);
DISPLAY INVISIBLE (900 825);
FORCEPROP 0 LAST $SEC 1
J 0
(850 750);
DISPLAY 0.680851 (850 750);
PAINT MONO (850 750);
DISPLAY INVISIBLE (850 750);
FORCEPROP 0 LAST CDS_SEC 1
J 0
(900 825);
DISPLAY INVISIBLE (900 825);
FORCEPROP 1 LASTPIN (850 675) $PN 1
J 0
(862 687);
DISPLAY 0.787234 (862 687);
PAINT MONO (862 687);
DISPLAY INVISIBLE (862 687);
FORCEPROP 1 LASTPIN (1050 675) $PN 2
J 0
(1012 687);
DISPLAY 0.787234 (1012 687);
PAINT MONO (1012 687);
DISPLAY INVISIBLE (1012 687);
FORCEADD Q_RES..2
(900 1150);
FORCEPROP 1 LAST PART_NUMBER CS11002FB07
J 0
(950 1100);
DISPLAY 0.510638 (950 1100);
DISPLAY INVISIBLE (950 1100);
FORCEPROP 1 LAST TOLERANCE 1%
J 0
(950 1175);
DISPLAY 0.510638 (950 1175);
FORCEPROP 1 LAST WATTAGE 1/16W
J 0
(950 1150);
DISPLAY 0.510638 (950 1150);
FORCEPROP 1 LAST VALUE 100
J 0
(945 1200);
DISPLAY 0.510638 (945 1200);
FORCEPROP 1 LAST MATERIAL EMPTY
J 0
(950 1125);
DISPLAY 0.510638 (950 1125);
PAINT RED (950 1125);
FORCEPROP 1 LAST PACK_TYPE 0402LF
J 0
(950 1075);
DISPLAY 0.510638 (950 1075);
FORCEPROP 1 LAST LOCATION PR3950
J 0
(950 1225);
DISPLAY 0.510638 (950 1225);
FORCEPROP 1 LASTPIN (900 1250) $PN 1
J 0
(905 1212);
DISPLAY 0.510638 (905 1212);
PAINT MONO (905 1212);
FORCEPROP 1 LASTPIN (900 1050) $PN 2
J 0
(905 1060);
DISPLAY 0.510638 (905 1060);
PAINT MONO (905 1060);
FORCEPROP 2 LAST CDS_LIB pure_quanta
J 0
(900 1150);
DISPLAY INVISIBLE (900 1150);
FORCEPROP 1 LAST PATH I55
J 0
(950 1325);
DISPLAY 0.978723 (950 1325);
PAINT WHITE (950 1325);
DISPLAY INVISIBLE (950 1325);
FORCEPROP 0 LAST $SEC 1
J 0
(950 1325);
DISPLAY 0.680851 (950 1325);
PAINT MONO (950 1325);
DISPLAY INVISIBLE (950 1325);
FORCEPROP 0 LAST CDS_SEC 1
J 0
(950 1325);
DISPLAY 1.021277 (950 1325);
DISPLAY INVISIBLE (950 1325);
FORCEADD Q_CAP..1
(975 300);
FORCEPROP 1 LAST PART_NUMBER CH4106K1B01
J 0
(1050 250);
DISPLAY 0.510638 (1050 250);
DISPLAY INVISIBLE (1050 250);
FORCEPROP 1 LAST PACK_TYPE C0402
J 0
(1050 225);
DISPLAY 0.510638 (1050 225);
FORCEPROP 1 LAST MATERIAL X7R
J 0
(1050 275);
DISPLAY 0.510638 (1050 275);
FORCEPROP 1 LAST VALUE 100NF
J 0
(1050 325);
DISPLAY 0.510638 (1050 325);
FORCEPROP 1 LAST VOLTAGE 50V
J 0
(1050 300);
DISPLAY 0.510638 (1050 300);
FORCEPROP 2 LAST ROOM E1S1_P12V_MPS_MAM_BOM3
J 0
(1050 400);
DISPLAY 0.404255 (1050 400);
FORCEPROP 1 LAST LOCATION PC2202
J 0
(1050 350);
DISPLAY 0.510638 (1050 350);
FORCEPROP 1 LAST TOLERANCE 10%
J 0
(1025 250);
DISPLAY 0.638298 (1025 250);
DISPLAY INVISIBLE (1025 250);
FORCEPROP 2 LAST CDS_LIB pure_quanta
J 0
(975 300);
DISPLAY INVISIBLE (975 300);
FORCEPROP 2 LAST ROOM1 E1S1_P12V_MPS_TIC_BOM4
J 0
(1050 450);
DISPLAY 1.021277 (1050 450);
DISPLAY INVISIBLE (1050 450);
FORCEPROP 1 LAST PATH I56
J 0
(1025 450);
DISPLAY 0.978723 (1025 450);
PAINT WHITE (1025 450);
DISPLAY INVISIBLE (1025 450);
FORCEPROP 0 LAST $SEC 1
J 0
(1025 450);
DISPLAY INVISIBLE (1025 450);
FORCEPROP 0 LAST CDS_SEC 1
J 0
(1025 450);
DISPLAY INVISIBLE (1025 450);
FORCEPROP 1 LASTPIN (975 400) $PN 1
J 0
(985 380);
DISPLAY 0.787234 (985 380);
PAINT MONO (985 380);
DISPLAY INVISIBLE (985 380);
FORCEPROP 1 LASTPIN (975 200) $PN 2
J 0
(985 180);
DISPLAY 0.787234 (985 180);
PAINT MONO (985 180);
DISPLAY INVISIBLE (985 180);
FORCEADD GND..1
(975 -100);
FORCEPROP 3 LASTPIN (975 -50) SIG_NAME GND\g
J 0
(985 -40);
DISPLAY 0.659574 (985 -40);
PAINT MONO (985 -40);
DISPLAY INVISIBLE (985 -40);
FORCEPROP 1 LAST HDL_POWER GND
J 0
(975 50);
DISPLAY 0.872340 (975 50);
PAINT GREEN (975 50);
DISPLAY INVISIBLE (975 50);
FORCEPROP 1 LAST SIZE 1B
J 0
(1050 -150);
DISPLAY 0.872340 (1050 -150);
PAINT GREEN (1050 -150);
DISPLAY INVISIBLE (1050 -150);
FORCEPROP 2 LAST CDS_LIB logical_power
J 0
(975 -100);
DISPLAY INVISIBLE (975 -100);
FORCEPROP 1 LAST PATH I57
J 0
(1050 -100);
DISPLAY 0.872340 (1050 -100);
PAINT AQUA (1050 -100);
DISPLAY INVISIBLE (1050 -100);
FORCEADD Q_RES..2
(1900 650);
FORCEPROP 1 LAST PART_NUMBER CS31002FB08
J 0
(1950 600);
DISPLAY 0.510638 (1950 600);
DISPLAY INVISIBLE (1950 600);
FORCEPROP 1 LAST TOLERANCE 1%
J 0
(1950 675);
DISPLAY 0.510638 (1950 675);
FORCEPROP 1 LAST VALUE 10K
J 0
(1950 700);
DISPLAY 0.510638 (1950 700);
FORCEPROP 2 LAST ROOM E1S1_P12V_MPS_MAM_BOM3
J 0
(1950 775);
DISPLAY 0.404255 (1950 775);
FORCEPROP 1 LAST PACK_TYPE 0402LF
J 0
(1950 575);
DISPLAY 0.510638 (1950 575);
FORCEPROP 1 LAST WATTAGE 1/16W
J 0
(1950 650);
DISPLAY 0.510638 (1950 650);
FORCEPROP 1 LAST MATERIAL CHIP
J 0
(1950 625);
DISPLAY 0.510638 (1950 625);
FORCEPROP 1 LAST LOCATION PR3954
J 0
(1950 725);
DISPLAY 0.510638 (1950 725);
FORCEPROP 2 LAST CDS_LIB pure_quanta
J 0
(1900 650);
DISPLAY INVISIBLE (1900 650);
FORCEPROP 2 LAST ROOM1 E1S1_P12V_MPS_TIC_BOM4
J 0
(1950 825);
DISPLAY 1.021277 (1950 825);
DISPLAY INVISIBLE (1950 825);
FORCEPROP 1 LAST PATH I58
J 0
(1950 825);
DISPLAY 0.978723 (1950 825);
PAINT WHITE (1950 825);
DISPLAY INVISIBLE (1950 825);
FORCEPROP 0 LAST $SEC 1
J 0
(1950 825);
DISPLAY INVISIBLE (1950 825);
FORCEPROP 0 LAST CDS_SEC 1
J 0
(1950 825);
DISPLAY INVISIBLE (1950 825);
FORCEPROP 1 LASTPIN (1900 750) $PN 1
J 0
(1905 712);
DISPLAY 0.787234 (1905 712);
PAINT MONO (1905 712);
DISPLAY INVISIBLE (1905 712);
FORCEPROP 1 LASTPIN (1900 550) $PN 2
J 0
(1905 560);
DISPLAY 0.787234 (1905 560);
PAINT MONO (1905 560);
DISPLAY INVISIBLE (1905 560);
FORCEADD OFFPAGE..1
R 2
(1100 925);
PAINT AQUA (1100 925);
FORCEPROP 2 LAST $XR0 193 
J 0
(1286 925);
DISPLAY 0.638298 (1286 925);
PAINT MONO (1286 925);
FORCEPROP 1 LAST COMMENT_BODY TRUE
J 2
(975 825);
DISPLAY 0.872340 (975 825);
PAINT GREEN (975 825);
DISPLAY INVISIBLE (975 825);
FORCEPROP 1 LAST OFFPAGE TRUE
J 2
(775 800);
DISPLAY 0.872340 (775 800);
PAINT AQUA (775 800);
DISPLAY INVISIBLE (775 800);
FORCEPROP 2 LAST CDS_LIB standard
J 2
(1100 925);
DISPLAY INVISIBLE (1100 925);
FORCEPROP 2 LAST PATH I59
J 0
(1300 950);
DISPLAY 1.021277 (1300 950);
DISPLAY INVISIBLE (1300 950);
FORCEADD Q_RES..1
R 1
(-425 -1675);
FORCEPROP 1 LAST PART_NUMBER CS22802FB04
J 0
(-375 -1725);
DISPLAY 0.510638 (-375 -1725);
DISPLAY INVISIBLE (-375 -1725);
FORCEPROP 1 LAST TOLERANCE 1%
J 0
(-375 -1675);
DISPLAY 0.510638 (-375 -1675);
FORCEPROP 1 LAST VALUE 2.8K
J 0
(-375 -1650);
DISPLAY 0.510638 (-375 -1650);
FORCEPROP 1 LAST PACK_TYPE 0402LF
J 0
(-375 -1750);
DISPLAY 0.510638 (-375 -1750);
FORCEPROP 1 LAST MATERIAL EMPTY
J 0
(-375 -1700);
DISPLAY 0.510638 (-375 -1700);
PAINT RED (-375 -1700);
FORCEPROP 2 LAST ROOM E1S1_P3V3_BOM2
J 0
(-375 -1575);
DISPLAY 0.510638 (-375 -1575);
FORCEPROP 1 LAST LOCATION PR3947
J 0
(-375 -1625);
DISPLAY 0.510638 (-375 -1625);
FORCEPROP 2 LAST CDS_LIB pure_quanta
R 1
J 0
(-425 -1675);
DISPLAY INVISIBLE (-425 -1675);
FORCEPROP 1 LAST WATTAGE 1/16W
R 1
J 2
(-275 -1700);
DISPLAY 0.978723 (-275 -1700);
DISPLAY INVISIBLE (-275 -1700);
FORCEPROP 1 LAST PATH I6
R 1
J 0
(-575 -1725);
DISPLAY 0.978723 (-575 -1725);
PAINT WHITE (-575 -1725);
DISPLAY INVISIBLE (-575 -1725);
FORCEPROP 0 LAST $SEC 1
R 1
J 0
(-400 -1600);
DISPLAY INVISIBLE (-400 -1600);
FORCEPROP 0 LAST CDS_SEC 1
R 1
J 0
(-400 -1600);
DISPLAY INVISIBLE (-400 -1600);
FORCEPROP 1 LASTPIN (-425 -1775) $PN 1
R 1
J 0
(-437 -1763);
DISPLAY 0.787234 (-437 -1763);
PAINT MONO (-437 -1763);
DISPLAY INVISIBLE (-437 -1763);
FORCEPROP 1 LASTPIN (-425 -1575) $PN 2
R 1
J 0
(-437 -1613);
DISPLAY 0.787234 (-437 -1613);
PAINT MONO (-437 -1613);
DISPLAY INVISIBLE (-437 -1613);
FORCEADD OFFPAGE..2
(1175 1525);
PAINT AQUA (1175 1525);
FORCEPROP 2 LAST $XR1 216 
J 0
(1364 1489);
DISPLAY 0.638298 (1364 1489);
PAINT MONO (1364 1489);
FORCEPROP 2 LAST $XR0 192 
J 0
(1364 1525);
DISPLAY 0.638298 (1364 1525);
PAINT MONO (1364 1525);
FORCEPROP 1 LAST COMMENT_BODY TRUE
J 0
(1130 1430);
DISPLAY 0.872340 (1130 1430);
PAINT GREEN (1130 1430);
DISPLAY INVISIBLE (1130 1430);
FORCEPROP 1 LAST OFFPAGE TRUE
J 0
(1500 1400);
DISPLAY 0.872340 (1500 1400);
PAINT AQUA (1500 1400);
DISPLAY INVISIBLE (1500 1400);
FORCEPROP 2 LAST CDS_LIB standard
J 0
(1175 1525);
DISPLAY INVISIBLE (1175 1525);
FORCEPROP 2 LAST PATH I60
J 0
(1375 1550);
DISPLAY 1.021277 (1375 1550);
DISPLAY INVISIBLE (1375 1550);
FORCEADD VCCAUX15..1
(1525 725);
FORCEPROP 3 LASTPIN (1525 675) SIG_NAME P3V3_AUX\g
J 0
(1535 685);
DISPLAY 0.659574 (1535 685);
PAINT MONO (1535 685);
DISPLAY INVISIBLE (1535 685);
FORCEPROP 1 LAST HDL_POWER P3V3_AUX
J 1
(1525 750);
DISPLAY 0.510638 (1525 750);
PAINT GREEN (1525 750);
FORCEPROP 2 LAST CDS_LIB logical_power
J 0
(1525 725);
DISPLAY INVISIBLE (1525 725);
FORCEPROP 1 LAST PATH I61
J 0
(1575 750);
DISPLAY 0.872340 (1575 750);
PAINT AQUA (1575 750);
DISPLAY INVISIBLE (1575 750);
FORCEADD Q_RES..2
(1500 1150);
FORCEPROP 1 LAST PART_NUMBER CS37152FB05
J 0
(1550 1100);
DISPLAY 0.510638 (1550 1100);
DISPLAY INVISIBLE (1550 1100);
FORCEPROP 1 LAST TOLERANCE 1%
J 0
(1550 1150);
DISPLAY 0.510638 (1550 1150);
FORCEPROP 1 LAST MATERIAL EMPTY
J 0
(1550 1125);
DISPLAY 0.510638 (1550 1125);
PAINT RED (1550 1125);
FORCEPROP 1 LAST PACK_TYPE 0402LF
J 0
(1550 1075);
DISPLAY 0.510638 (1550 1075);
FORCEPROP 1 LAST VALUE 71.5K
J 0
(1550 1175);
DISPLAY 0.510638 (1550 1175);
FORCEPROP 1 LAST LOCATION PR3952
J 0
(1550 1200);
DISPLAY 0.510638 (1550 1200);
FORCEPROP 1 LASTPIN (1500 1250) $PN 1
J 0
(1505 1212);
DISPLAY 0.510638 (1505 1212);
FORCEPROP 1 LASTPIN (1500 1050) $PN 2
J 0
(1505 1060);
DISPLAY 0.510638 (1505 1060);
FORCEPROP 2 LAST CDS_LIB pure_quanta
J 0
(1500 1150);
DISPLAY INVISIBLE (1500 1150);
FORCEPROP 1 LAST WATTAGE 1/16W
J 0
(1525 1125);
DISPLAY 0.723404 (1525 1125);
PAINT SKYBLUE (1525 1125);
DISPLAY INVISIBLE (1525 1125);
FORCEPROP 1 LAST PATH I62
J 0
(1550 1325);
DISPLAY 0.978723 (1550 1325);
PAINT WHITE (1550 1325);
DISPLAY INVISIBLE (1550 1325);
FORCEPROP 0 LAST $SEC 1
J 0
(1525 1275);
DISPLAY 0.680851 (1525 1275);
PAINT MONO (1525 1275);
DISPLAY INVISIBLE (1525 1275);
FORCEPROP 0 LAST CDS_SEC 1
J 0
(1525 1275);
DISPLAY 1.021277 (1525 1275);
DISPLAY INVISIBLE (1525 1275);
FORCEADD Q_RES..2
(1900 1075);
FORCEPROP 1 LAST PART_NUMBER CS41202FB05
J 0
(1950 1000);
DISPLAY 0.510638 (1950 1000);
DISPLAY INVISIBLE (1950 1000);
FORCEPROP 1 LAST TOLERANCE 1%
J 0
(1950 1075);
DISPLAY 0.510638 (1950 1075);
FORCEPROP 1 LAST PACK_TYPE 0402LF
J 0
(1950 975);
DISPLAY 0.510638 (1950 975);
FORCEPROP 1 LAST VALUE 120K
J 0
(1950 1100);
DISPLAY 0.510638 (1950 1100);
FORCEPROP 1 LAST WATTAGE 1/16W
J 0
(1950 1050);
DISPLAY 0.510638 (1950 1050);
FORCEPROP 1 LAST MATERIAL CHIP
J 0
(1950 1025);
DISPLAY 0.510638 (1950 1025);
FORCEPROP 2 LAST ROOM E1S1_P12V_MPS_MAM_BOM3
J 0
(1950 1175);
DISPLAY 0.404255 (1950 1175);
FORCEPROP 1 LAST LOCATION PR3953
J 0
(1950 1125);
DISPLAY 0.510638 (1950 1125);
FORCEPROP 2 LAST CDS_LIB pure_quanta
J 0
(1900 1075);
DISPLAY INVISIBLE (1900 1075);
FORCEPROP 2 LAST ROOM1 E1S1_P12V_MPS_TIC_BOM4
J 0
(1950 1225);
DISPLAY 1.021277 (1950 1225);
DISPLAY INVISIBLE (1950 1225);
FORCEPROP 1 LAST PATH I63
J 0
(1950 1250);
DISPLAY 0.978723 (1950 1250);
PAINT WHITE (1950 1250);
DISPLAY INVISIBLE (1950 1250);
FORCEPROP 0 LAST $SEC 1
J 0
(1950 1250);
DISPLAY INVISIBLE (1950 1250);
FORCEPROP 0 LAST CDS_SEC 1
J 0
(1950 1250);
DISPLAY INVISIBLE (1950 1250);
FORCEPROP 1 LASTPIN (1900 1175) $PN 1
J 0
(1905 1137);
DISPLAY 0.787234 (1905 1137);
PAINT MONO (1905 1137);
DISPLAY INVISIBLE (1905 1137);
FORCEPROP 1 LASTPIN (1900 975) $PN 2
J 0
(1905 985);
DISPLAY 0.787234 (1905 985);
PAINT MONO (1905 985);
DISPLAY INVISIBLE (1905 985);
FORCEADD Q_RES..2
(375 1750);
FORCEPROP 1 LAST PART_NUMBER CS31002FB08
J 0
(450 1700);
DISPLAY 0.510638 (450 1700);
DISPLAY INVISIBLE (450 1700);
FORCEPROP 1 LAST PACK_TYPE 0402LF
J 0
(450 1675);
DISPLAY 0.510638 (450 1675);
FORCEPROP 1 LAST WATTAGE 1/16W
J 0
(450 1750);
DISPLAY 0.510638 (450 1750);
FORCEPROP 2 LAST ROOM E1S1_P12V_MPS_MAM_BOM3
J 0
(450 1875);
DISPLAY 0.510638 (450 1875);
FORCEPROP 1 LAST TOLERANCE 1%
J 0
(450 1775);
DISPLAY 0.510638 (450 1775);
FORCEPROP 1 LAST MATERIAL CHIP
J 0
(450 1725);
DISPLAY 0.510638 (450 1725);
FORCEPROP 1 LAST VALUE 10K
J 0
(450 1800);
DISPLAY 0.510638 (450 1800);
FORCEPROP 1 LAST LOCATION R3948
J 0
(450 1825);
DISPLAY 0.510638 (450 1825);
FORCEPROP 1 LASTPIN (375 1850) $PN 1
J 0
(380 1812);
DISPLAY 0.510638 (380 1812);
PAINT MONO (380 1812);
FORCEPROP 1 LASTPIN (375 1650) $PN 2
J 0
(380 1660);
DISPLAY 0.510638 (380 1660);
PAINT MONO (380 1660);
FORCEPROP 2 LAST CDS_LIB pure_quanta
J 0
(375 1750);
DISPLAY INVISIBLE (375 1750);
FORCEPROP 2 LAST ROOM1 E1S1_P12V_MPS_TIC_BOM4
J 0
(450 1925);
DISPLAY 1.021277 (450 1925);
DISPLAY INVISIBLE (450 1925);
FORCEPROP 1 LAST PATH I64
J 0
(425 1925);
DISPLAY 0.978723 (425 1925);
PAINT WHITE (425 1925);
DISPLAY INVISIBLE (425 1925);
FORCEPROP 0 LAST $SEC 1
J 0
(430 1967);
DISPLAY 0.680851 (430 1967);
PAINT MONO (430 1967);
DISPLAY INVISIBLE (430 1967);
FORCEPROP 0 LAST CDS_SEC 1
J 0
(425 1925);
DISPLAY INVISIBLE (425 1925);
FORCEADD VCCAUX15..1
(375 1950);
FORCEPROP 3 LASTPIN (375 1900) SIG_NAME P3V3_AUX\g
J 0
(385 1910);
DISPLAY 0.659574 (385 1910);
PAINT MONO (385 1910);
DISPLAY INVISIBLE (385 1910);
FORCEPROP 1 LAST HDL_POWER P3V3_AUX
J 1
(375 2000);
DISPLAY 0.510638 (375 2000);
PAINT GREEN (375 2000);
FORCEPROP 2 LAST CDS_LIB logical_power
J 0
(375 1950);
DISPLAY INVISIBLE (375 1950);
FORCEPROP 1 LAST PATH I65
J 0
(425 1975);
DISPLAY 0.872340 (425 1975);
PAINT AQUA (425 1975);
DISPLAY INVISIBLE (425 1975);
FORCEADD Q_RES..1
(2325 -25);
FORCEPROP 1 LAST PART_NUMBER CS00002JB13
J 0
(2150 -75);
DISPLAY 0.510638 (2150 -75);
DISPLAY INVISIBLE (2150 -75);
FORCEPROP 1 LAST VALUE 0
J 2
(2475 -25);
DISPLAY 0.510638 (2475 -25);
FORCEPROP 0 LAST ROOM1 E1S1_P12V_MPS_TIC_BOM4
J 0
(2050 -125);
DISPLAY 0.510638 (2050 -125);
FORCEPROP 1 LAST PACK_TYPE 0402LF
J 0
(2475 -75);
DISPLAY 0.510638 (2475 -75);
FORCEPROP 1 LAST WATTAGE 1/16W
J 2
(2125 -75);
DISPLAY 0.510638 (2125 -75);
FORCEPROP 1 LAST MATERIAL CHIP
J 0
(2100 -25);
DISPLAY 0.510638 (2100 -25);
FORCEPROP 1 LAST TOLERANCE 5%
J 0
(2500 -25);
DISPLAY 0.510638 (2500 -25);
FORCEPROP 1 LAST $LOCATION R3956
J 0
(2275 25);
DISPLAY 0.510638 (2275 25);
FORCEPROP 1 LASTPIN (2225 -25) $PN 1
J 0
(2237 -13);
DISPLAY 0.510638 (2237 -13);
PAINT MONO (2237 -13);
FORCEPROP 1 LASTPIN (2425 -25) $PN 2
J 0
(2387 -13);
DISPLAY 0.510638 (2387 -13);
PAINT MONO (2387 -13);
FORCEPROP 1 LAST PATH I66
J 0
(2275 125);
DISPLAY 0.978723 (2275 125);
PAINT WHITE (2275 125);
DISPLAY INVISIBLE (2275 125);
FORCEPROP 2 LAST CDS_LIB pure_quanta
J 0
(2325 -25);
DISPLAY INVISIBLE (2325 -25);
FORCEPROP 0 LAST CDS_LOCATION R3956
J 0
(2275 75);
DISPLAY 1.021277 (2275 75);
DISPLAY INVISIBLE (2275 75);
FORCEPROP 0 LAST $SEC 1
J 0
(2275 75);
DISPLAY 0.680851 (2275 75);
PAINT MONO (2275 75);
DISPLAY INVISIBLE (2275 75);
FORCEPROP 0 LAST CDS_SEC 1
J 0
(2275 75);
DISPLAY 1.021277 (2275 75);
DISPLAY INVISIBLE (2275 75);
FORCEADD Q_RES..1
(2325 150);
FORCEPROP 1 LAST PART_NUMBER CS00002JB13
J 0
(2150 100);
DISPLAY 0.510638 (2150 100);
DISPLAY INVISIBLE (2150 100);
FORCEPROP 2 LAST ROOM E1S1_P12V_MPS_MAM_BOM3
J 0
(2075 250);
DISPLAY 0.510638 (2075 250);
FORCEPROP 1 LAST VALUE 0
J 2
(2475 150);
DISPLAY 0.510638 (2475 150);
FORCEPROP 1 LAST TOLERANCE 5%
J 0
(2500 150);
DISPLAY 0.510638 (2500 150);
FORCEPROP 1 LAST WATTAGE 1/16W
J 2
(2125 100);
DISPLAY 0.510638 (2125 100);
FORCEPROP 1 LAST PACK_TYPE 0402LF
J 0
(2475 100);
DISPLAY 0.510638 (2475 100);
FORCEPROP 1 LAST MATERIAL EMPTY
J 0
(2100 150);
DISPLAY 0.510638 (2100 150);
PAINT RED (2100 150);
FORCEPROP 1 LAST $LOCATION R3955
J 0
(2275 200);
DISPLAY 0.510638 (2275 200);
FORCEPROP 1 LASTPIN (2225 150) $PN 1
J 0
(2237 162);
DISPLAY 0.510638 (2237 162);
PAINT MONO (2237 162);
FORCEPROP 1 LASTPIN (2425 150) $PN 2
J 0
(2387 162);
DISPLAY 0.510638 (2387 162);
PAINT MONO (2387 162);
FORCEPROP 1 LAST PATH I67
J 0
(2275 300);
DISPLAY 0.978723 (2275 300);
PAINT WHITE (2275 300);
DISPLAY INVISIBLE (2275 300);
FORCEPROP 2 LAST CDS_LIB pure_quanta
J 0
(2325 150);
DISPLAY INVISIBLE (2325 150);
FORCEPROP 0 LAST CDS_LOCATION R3955
J 0
(2275 250);
DISPLAY 1.021277 (2275 250);
DISPLAY INVISIBLE (2275 250);
FORCEPROP 0 LAST $SEC 1
J 0
(2275 250);
DISPLAY 0.680851 (2275 250);
PAINT MONO (2275 250);
DISPLAY INVISIBLE (2275 250);
FORCEPROP 0 LAST CDS_SEC 1
J 0
(2275 250);
DISPLAY 1.021277 (2275 250);
DISPLAY INVISIBLE (2275 250);
FORCEADD GND..1
(2100 325);
FORCEPROP 3 LASTPIN (2100 375) SIG_NAME GND\g
J 0
(2110 385);
DISPLAY 0.659574 (2110 385);
PAINT MONO (2110 385);
DISPLAY INVISIBLE (2110 385);
FORCEPROP 1 LAST HDL_POWER GND
J 0
(2100 475);
DISPLAY 0.872340 (2100 475);
PAINT GREEN (2100 475);
DISPLAY INVISIBLE (2100 475);
FORCEPROP 2 LAST CDS_LIB logical_power
J 0
(2100 325);
DISPLAY INVISIBLE (2100 325);
FORCEPROP 1 LAST SIZE 1B
J 0
(2175 275);
DISPLAY 0.872340 (2175 275);
PAINT GREEN (2175 275);
DISPLAY INVISIBLE (2175 275);
FORCEPROP 1 LAST PATH I68
J 0
(2175 325);
DISPLAY 0.872340 (2175 325);
PAINT AQUA (2175 325);
DISPLAY INVISIBLE (2175 325);
FORCEADD Q_CAP..1
(2425 650);
FORCEPROP 1 LAST PART_NUMBER CH5223M1900
J 0
(2500 575);
DISPLAY 0.510638 (2500 575);
DISPLAY INVISIBLE (2500 575);
FORCEPROP 1 LAST TOLERANCE 20%
J 0
(2500 625);
DISPLAY 0.510638 (2500 625);
FORCEPROP 1 LAST VALUE 2.2UF
J 0
(2500 675);
DISPLAY 0.510638 (2500 675);
FORCEPROP 1 LAST MATERIAL X7R
J 0
(2500 600);
DISPLAY 0.510638 (2500 600);
FORCEPROP 1 LAST PACK_TYPE C0603
J 0
(2500 550);
DISPLAY 0.510638 (2500 550);
FORCEPROP 1 LAST VOLTAGE 16V
J 0
(2500 650);
DISPLAY 0.510638 (2500 650);
FORCEPROP 2 LAST ROOM E1S1_P12V_MPS_MAM_BOM3
J 0
(2500 750);
DISPLAY 0.510638 (2500 750);
FORCEPROP 1 LAST LOCATION PC2205
J 0
(2500 700);
DISPLAY 0.510638 (2500 700);
FORCEPROP 2 LAST CDS_LIB pure_quanta
J 0
(2425 650);
DISPLAY INVISIBLE (2425 650);
FORCEPROP 2 LAST ROOM1 E1S1_P12V_MPS_TIC_BOM4
J 0
(2500 800);
DISPLAY 1.021277 (2500 800);
DISPLAY INVISIBLE (2500 800);
FORCEPROP 1 LAST PATH I69
J 0
(2475 800);
DISPLAY 0.978723 (2475 800);
PAINT WHITE (2475 800);
DISPLAY INVISIBLE (2475 800);
FORCEPROP 0 LAST $SEC 1
J 0
(2500 800);
DISPLAY INVISIBLE (2500 800);
FORCEPROP 0 LAST CDS_SEC 1
J 0
(2500 800);
DISPLAY INVISIBLE (2500 800);
FORCEPROP 1 LASTPIN (2425 750) $PN 1
J 0
(2435 730);
DISPLAY 0.787234 (2435 730);
PAINT MONO (2435 730);
DISPLAY INVISIBLE (2435 730);
FORCEPROP 1 LASTPIN (2425 550) $PN 2
J 0
(2435 530);
DISPLAY 0.787234 (2435 530);
PAINT MONO (2435 530);
DISPLAY INVISIBLE (2435 530);
FORCEADD UNIVERSAL_GND..1
(-425 -2000);
FORCEPROP 3 LASTPIN (-425 -1950) SIG_NAME GND\g
J 0
(-415 -1940);
DISPLAY 0.659574 (-415 -1940);
PAINT MONO (-415 -1940);
DISPLAY INVISIBLE (-415 -1940);
FORCEPROP 2 LAST CDS_LIB logical_power
J 0
(-425 -2000);
DISPLAY INVISIBLE (-425 -2000);
FORCEPROP 1 LAST HDL_POWER GND
J 1
(-400 -2075);
DISPLAY 0.872340 (-400 -2075);
PAINT GREEN (-400 -2075);
DISPLAY INVISIBLE (-400 -2075);
FORCEPROP 1 LAST PATH I7
J 0
(-350 -2000);
DISPLAY 0.872340 (-350 -2000);
PAINT AQUA (-350 -2000);
DISPLAY INVISIBLE (-350 -2000);
FORCEADD Q_RES..2
(2425 1075);
FORCEPROP 1 LAST PART_NUMBER CS04993F909
J 0
(2500 1000);
DISPLAY 0.510638 (2500 1000);
DISPLAY INVISIBLE (2500 1000);
FORCEPROP 1 LAST VALUE 49.9
J 0
(2500 1100);
DISPLAY 0.510638 (2500 1100);
FORCEPROP 1 LAST PACK_TYPE 0603LF
J 0
(2500 975);
DISPLAY 0.510638 (2500 975);
FORCEPROP 1 LAST MATERIAL CHIP
J 0
(2500 1025);
DISPLAY 0.510638 (2500 1025);
FORCEPROP 1 LAST WATTAGE 1/10W
J 0
(2500 1050);
DISPLAY 0.510638 (2500 1050);
FORCEPROP 1 LAST TOLERANCE 1%
J 0
(2500 1075);
DISPLAY 0.510638 (2500 1075);
FORCEPROP 2 LAST ROOM E1S1_P12V_MPS_MAM_BOM3
J 0
(2500 1150);
DISPLAY 0.510638 (2500 1150);
FORCEPROP 1 LAST LOCATION PR3957
J 0
(2500 1125);
DISPLAY 0.510638 (2500 1125);
FORCEPROP 1 LASTPIN (2425 1175) $PN 1
J 0
(2430 1137);
DISPLAY 0.510638 (2430 1137);
PAINT MONO (2430 1137);
FORCEPROP 1 LASTPIN (2425 975) $PN 2
J 0
(2430 985);
DISPLAY 0.510638 (2430 985);
PAINT MONO (2430 985);
FORCEPROP 2 LAST CDS_LIB pure_quanta
J 0
(2425 1075);
DISPLAY INVISIBLE (2425 1075);
FORCEPROP 2 LAST ROOM1 E1S1_P12V_MPS_TIC_BOM4
J 0
(2500 1200);
DISPLAY 1.021277 (2500 1200);
DISPLAY INVISIBLE (2500 1200);
FORCEPROP 1 LAST PATH I70
J 0
(2475 1250);
DISPLAY 0.978723 (2475 1250);
PAINT WHITE (2475 1250);
DISPLAY INVISIBLE (2475 1250);
FORCEPROP 0 LAST $SEC 1
J 0
(2475 1250);
DISPLAY 0.680851 (2475 1250);
PAINT MONO (2475 1250);
DISPLAY INVISIBLE (2475 1250);
FORCEPROP 0 LAST CDS_SEC 1
J 0
(2475 1250);
DISPLAY 1.021277 (2475 1250);
DISPLAY INVISIBLE (2475 1250);
FORCEADD UNIVERSAL_POWER..1
(2325 1375);
FORCEPROP 3 LASTPIN (2325 1325) SIG_NAME P12V_AUX\g
J 0
(2335 1335);
DISPLAY 0.659574 (2335 1335);
PAINT MONO (2335 1335);
DISPLAY INVISIBLE (2335 1335);
FORCEPROP 1 LAST HDL_POWER P12V_AUX
J 1
(2325 1425);
DISPLAY 0.510638 (2325 1425);
PAINT GREEN (2325 1425);
FORCEPROP 2 LAST CDS_LIB logical_power
J 0
(2325 1375);
DISPLAY INVISIBLE (2325 1375);
FORCEPROP 1 LAST PATH I71
J 0
(2375 1400);
DISPLAY 0.872340 (2375 1400);
PAINT AQUA (2375 1400);
DISPLAY INVISIBLE (2375 1400);
FORCEADD GND..1
(2775 1225);
FORCEPROP 3 LASTPIN (2775 1275) SIG_NAME GND\g
J 0
(2785 1285);
DISPLAY 0.659574 (2785 1285);
PAINT MONO (2785 1285);
DISPLAY INVISIBLE (2785 1285);
FORCEPROP 1 LAST HDL_POWER GND
J 0
(2775 1375);
DISPLAY 0.872340 (2775 1375);
PAINT GREEN (2775 1375);
DISPLAY INVISIBLE (2775 1375);
FORCEPROP 1 LAST SIZE 1B
J 0
(2850 1175);
DISPLAY 0.872340 (2850 1175);
PAINT GREEN (2850 1175);
DISPLAY INVISIBLE (2850 1175);
FORCEPROP 2 LAST CDS_LIB logical_power
J 0
(2775 1225);
DISPLAY INVISIBLE (2775 1225);
FORCEPROP 1 LAST PATH I72
J 0
(2850 1225);
DISPLAY 0.872340 (2850 1225);
PAINT AQUA (2850 1225);
DISPLAY INVISIBLE (2850 1225);
FORCEADD Q_CAP..1
R 2
(2775 1500);
FORCEPROP 1 LAST PART_NUMBER CH4104K1B00
J 0
(2850 1425);
DISPLAY 0.510638 (2850 1425);
DISPLAY INVISIBLE (2850 1425);
FORCEPROP 1 LAST VOLTAGE 25V
J 0
(2850 1500);
DISPLAY 0.510638 (2850 1500);
FORCEPROP 1 LAST MATERIAL X7R
J 0
(2850 1450);
DISPLAY 0.510638 (2850 1450);
FORCEPROP 1 LAST PACK_TYPE 0402
J 0
(2850 1400);
DISPLAY 0.510638 (2850 1400);
FORCEPROP 1 LAST TOLERANCE 10%
J 0
(2850 1475);
DISPLAY 0.510638 (2850 1475);
FORCEPROP 1 LAST VALUE 0.1UF
J 0
(2850 1525);
DISPLAY 0.510638 (2850 1525);
FORCEPROP 2 LAST ROOM E1S1_P12V_MPS_MAM_BOM3
J 0
(2850 1600);
DISPLAY 0.510638 (2850 1600);
FORCEPROP 1 LAST LOCATION PC2206
J 0
(2850 1550);
DISPLAY 0.510638 (2850 1550);
FORCEPROP 1 LASTPIN (2775 1600) $PN 1
J 2
(2765 1580);
DISPLAY 0.510638 (2765 1580);
PAINT MONO (2765 1580);
FORCEPROP 1 LASTPIN (2775 1400) $PN 2
J 2
(2765 1380);
DISPLAY 0.510638 (2765 1380);
PAINT MONO (2765 1380);
FORCEPROP 2 LAST CDS_LIB pure_quanta
J 0
(2775 1500);
DISPLAY INVISIBLE (2775 1500);
FORCEPROP 2 LAST ROOM1 E1S1_P12V_MPS_TIC_BOM4
J 0
(2850 1650);
DISPLAY 1.021277 (2850 1650);
DISPLAY INVISIBLE (2850 1650);
FORCEPROP 1 LAST PATH I73
J 2
(2725 1650);
DISPLAY 0.978723 (2725 1650);
PAINT WHITE (2725 1650);
DISPLAY INVISIBLE (2725 1650);
FORCEPROP 0 LAST $SEC 1
J 0
(3125 1650);
DISPLAY 0.680851 (3125 1650);
PAINT MONO (3125 1650);
DISPLAY INVISIBLE (3125 1650);
FORCEPROP 0 LAST CDS_SEC 1
J 0
(3125 1650);
DISPLAY 1.021277 (3125 1650);
DISPLAY INVISIBLE (3125 1650);
FORCEADD OFFPAGE..2
(3550 -25);
PAINT AQUA (3550 -25);
FORCEPROP 2 LAST $XR0 250 
J 0
(3739 -25);
DISPLAY 0.638298 (3739 -25);
PAINT MONO (3739 -25);
FORCEPROP 1 LAST COMMENT_BODY TRUE
J 0
(3505 -120);
DISPLAY 0.872340 (3505 -120);
PAINT GREEN (3505 -120);
DISPLAY INVISIBLE (3505 -120);
FORCEPROP 1 LAST OFFPAGE TRUE
J 0
(3875 -150);
DISPLAY 0.872340 (3875 -150);
PAINT AQUA (3875 -150);
DISPLAY INVISIBLE (3875 -150);
FORCEPROP 2 LAST CDS_LIB standard
J 0
(3550 -25);
DISPLAY INVISIBLE (3550 -25);
FORCEPROP 2 LAST PATH I74
J 0
(3750 25);
DISPLAY 1.021277 (3750 25);
DISPLAY INVISIBLE (3750 25);
FORCEADD OFFPAGE..2
(3575 150);
PAINT AQUA (3575 150);
FORCEPROP 2 LAST $XR0 250 
J 0
(3764 150);
DISPLAY 0.638298 (3764 150);
PAINT MONO (3764 150);
FORCEPROP 1 LAST COMMENT_BODY TRUE
J 0
(3530 55);
DISPLAY 0.872340 (3530 55);
PAINT GREEN (3530 55);
DISPLAY INVISIBLE (3530 55);
FORCEPROP 1 LAST OFFPAGE TRUE
J 0
(3900 25);
DISPLAY 0.872340 (3900 25);
PAINT AQUA (3900 25);
DISPLAY INVISIBLE (3900 25);
FORCEPROP 2 LAST CDS_LIB standard
J 0
(3575 150);
DISPLAY INVISIBLE (3575 150);
FORCEPROP 2 LAST PATH I75
J 0
(3775 200);
DISPLAY 1.021277 (3775 200);
DISPLAY INVISIBLE (3775 200);
FORCEADD OFFPAGE..2
(3075 800);
PAINT AQUA (3075 800);
FORCEPROP 2 LAST $XR0 193 
J 0
(3264 800);
DISPLAY 0.638298 (3264 800);
PAINT MONO (3264 800);
FORCEPROP 1 LAST COMMENT_BODY TRUE
J 0
(3030 705);
DISPLAY 0.872340 (3030 705);
PAINT GREEN (3030 705);
DISPLAY INVISIBLE (3030 705);
FORCEPROP 1 LAST OFFPAGE TRUE
J 0
(3400 675);
DISPLAY 0.872340 (3400 675);
PAINT AQUA (3400 675);
DISPLAY INVISIBLE (3400 675);
FORCEPROP 2 LAST CDS_LIB standard
J 0
(3075 800);
DISPLAY INVISIBLE (3075 800);
FORCEPROP 2 LAST PATH I76
J 0
(3275 825);
DISPLAY 1.021277 (3275 825);
DISPLAY INVISIBLE (3275 825);
FORCEADD UNIVERSAL_POWER..1
R 2
(2775 1775);
FORCEPROP 3 LASTPIN (2775 1725) SIG_NAME P12V_E1S_0\g
J 0
(2785 1735);
DISPLAY 0.659574 (2785 1735);
PAINT MONO (2785 1735);
DISPLAY INVISIBLE (2785 1735);
FORCEPROP 1 LAST HDL_POWER P12V_E1S_0
J 1
(2775 1825);
DISPLAY 0.510638 (2775 1825);
PAINT GREEN (2775 1825);
FORCEPROP 2 LAST CDS_LIB logical_power
J 0
(2775 1775);
DISPLAY INVISIBLE (2775 1775);
FORCEPROP 1 LAST PATH I77
J 2
(2725 1800);
DISPLAY 0.872340 (2725 1800);
PAINT AQUA (2725 1800);
DISPLAY INVISIBLE (2725 1800);
FORCEADD UNIVERSAL_GND..1
(-450 -1275);
FORCEPROP 3 LASTPIN (-450 -1225) SIG_NAME GND\g
J 0
(-440 -1215);
DISPLAY 0.659574 (-440 -1215);
PAINT MONO (-440 -1215);
DISPLAY INVISIBLE (-440 -1215);
FORCEPROP 2 LAST CDS_LIB logical_power
J 0
(-450 -1275);
DISPLAY INVISIBLE (-450 -1275);
FORCEPROP 1 LAST HDL_POWER GND
J 1
(-425 -1350);
DISPLAY 0.872340 (-425 -1350);
PAINT GREEN (-425 -1350);
DISPLAY INVISIBLE (-425 -1350);
FORCEPROP 1 LAST PATH I8
J 0
(-375 -1275);
DISPLAY 0.872340 (-375 -1275);
PAINT AQUA (-375 -1275);
DISPLAY INVISIBLE (-375 -1275);
FORCEADD Q_CAP..1
(-450 -1050);
FORCEPROP 1 LAST PART_NUMBER CH5104KEB02
J 0
(-375 -1100);
DISPLAY 0.510638 (-375 -1100);
DISPLAY INVISIBLE (-375 -1100);
FORCEPROP 1 LAST VOLTAGE 25V
J 0
(-375 -1050);
DISPLAY 0.510638 (-375 -1050);
FORCEPROP 1 LAST MATERIAL EMPTY
J 0
(-375 -1075);
DISPLAY 0.510638 (-375 -1075);
PAINT RED (-375 -1075);
FORCEPROP 1 LAST PACK_TYPE C0402
J 0
(-375 -1125);
DISPLAY 0.510638 (-375 -1125);
FORCEPROP 1 LAST VALUE 1UF
J 0
(-375 -1025);
DISPLAY 0.510638 (-375 -1025);
FORCEPROP 2 LAST ROOM E1S1_P3V3_BOM2
J 0
(-375 -950);
DISPLAY 0.510638 (-375 -950);
FORCEPROP 1 LAST LOCATION PC2200
J 0
(-375 -1000);
DISPLAY 0.510638 (-375 -1000);
FORCEPROP 1 LAST TOLERANCE 10%
J 0
(-400 -1100);
DISPLAY 0.638298 (-400 -1100);
DISPLAY INVISIBLE (-400 -1100);
FORCEPROP 2 LAST CDS_LIB pure_quanta
J 0
(-450 -1050);
DISPLAY INVISIBLE (-450 -1050);
FORCEPROP 1 LAST PATH I9
J 0
(-400 -900);
DISPLAY 0.978723 (-400 -900);
PAINT WHITE (-400 -900);
DISPLAY INVISIBLE (-400 -900);
FORCEPROP 0 LAST $SEC 1
J 0
(-400 -900);
DISPLAY INVISIBLE (-400 -900);
FORCEPROP 0 LAST CDS_SEC 1
J 0
(-400 -900);
DISPLAY INVISIBLE (-400 -900);
FORCEPROP 1 LASTPIN (-450 -950) $PN 1
J 0
(-440 -970);
DISPLAY 0.787234 (-440 -970);
PAINT MONO (-440 -970);
DISPLAY INVISIBLE (-440 -970);
FORCEPROP 1 LASTPIN (-450 -1150) $PN 2
J 0
(-440 -1170);
DISPLAY 0.787234 (-440 -1170);
PAINT MONO (-440 -1170);
DISPLAY INVISIBLE (-440 -1170);
FORCEADD QUANTA_TITLE_BLOCK_C..1
(4625 -3350);
FORCEPROP 0 LAST CDS_CON_LAST_MODIFIED Fri Aug 25 14:03:07 2023
J 0
(2740 -3335);
PAINT MONO (2740 -3335);
DISPLAY INVISIBLE (2740 -3335);
FORCEPROP 2 LAST CUSTOM_TXT_CDS <XR_PAGE_TITLE>
J 0
(-3265 1900);
DISPLAY 0.638298 (-3265 1900);
PAINT PINK (-3265 1900);
DISPLAY INVISIBLE (-3265 1900);
FORCEPROP 2 LAST CUSTOM_TXT_CDS <CON_PAGE_NUM> OF <CON_TOTAL_PAGES>
J 0
(4179 -3332);
DISPLAY 0.510638 (4179 -3332);
FORCEPROP 2 LAST CUSTOM_TXT_CDS <Q_REV>
J 0
(4441 -3247);
DISPLAY 0.510638 (4441 -3247);
FORCEPROP 2 LAST CUSTOM_TXT_CDS <CON_LAST_MODIFIED>
J 0
(2740 -3335);
DISPLAY 0.510638 (2740 -3335);
FORCEPROP 2 LAST CUSTOM_TXT_CDS <Q_PROJ>
J 0
(2243 -3248);
DISPLAY 0.510638 (2243 -3248);
FORCEPROP 2 LAST CUSTOM_TXT_CDS <Q_NUMBER>
J 0
(3222 -3247);
DISPLAY 0.510638 (3222 -3247);
FORCEPROP 2 LAST CUSTOM_TXT_CDS <NAME_2>
J 0
(1450 -3300);
DISPLAY 0.510638 (1450 -3300);
FORCEPROP 2 LAST CUSTOM_TXT_CDS <NAME_1>
J 0
(1450 -3175);
DISPLAY 0.510638 (1450 -3175);
FORCEPROP 1 LAST Q_TITLE E1S_HSC_CO_LAYOUT
J 0
(-4741 -3324);
DISPLAY 0.510638 (-4741 -3324);
PAINT GREEN (-4741 -3324);
FORCEPROP 1 LAST Q_DEPT 
J 1
(862 -3301);
DISPLAY 0.510638 (862 -3301);
PAINT GREEN (862 -3301);
FORCEPROP 2 LAST CDS_XR_PAGE_TITLE CR-193 : @S9S_MB_2U_LIB.S9S_MB_2U(SCH_1):PAGE193
J 0
(-3265 1900);
DISPLAY 0.638298 (-3265 1900);
PAINT PINK (-3265 1900);
DISPLAY INVISIBLE (-3265 1900);
FORCEPROP 1 LAST COMMENT_BODY TRUE
J 0
(4637 -3363);
DISPLAY 0.978723 (4637 -3363);
PAINT GREEN (4637 -3363);
DISPLAY INVISIBLE (4637 -3363);
FORCEPROP 2 LAST CDS_LIB pure_quanta
J 0
(4625 -3350);
PAINT MONO (4625 -3350);
DISPLAY INVISIBLE (4625 -3350);
FORCEPROP 1 LAST CDS_LMAN_SYM_OUTLINE -9475,6775,100,-125
J 0
(4625 -3350);
DISPLAY 0.468085 (4625 -3350);
PAINT GREEN (4625 -3350);
DISPLAY INVISIBLE (4625 -3350);
FORCEPROP 2 LAST PAGE_BORDER TRUE
J 0
(-3265 1900);
DISPLAY 0.638298 (-3265 1900);
PAINT PINK (-3265 1900);
DISPLAY INVISIBLE (-3265 1900);
FORCEADD DNS..2
(2350 150);
PAINT RED (2350 150);
FORCEPROP 1 LAST COMMENT_BODY TRUE
R 1
J 0
(2425 -75);
DISPLAY 0.872340 (2425 -75);
PAINT GREEN (2425 -75);
DISPLAY INVISIBLE (2425 -75);
FORCEPROP 2 LAST CDS_LIB mstr_misc
J 0
(2350 150);
DISPLAY INVISIBLE (2350 150);
FORCEADD DNS..2
(925 1150);
PAINT RED (925 1150);
FORCEPROP 1 LAST COMMENT_BODY TRUE
R 1
J 0
(1000 925);
DISPLAY 0.872340 (1000 925);
PAINT GREEN (1000 925);
DISPLAY INVISIBLE (1000 925);
FORCEPROP 2 LAST CDS_LIB mstr_misc
J 0
(925 1150);
DISPLAY INVISIBLE (925 1150);
FORCEADD DNS..2
(1525 1150);
PAINT RED (1525 1150);
FORCEPROP 1 LAST COMMENT_BODY TRUE
R 1
J 0
(1600 925);
DISPLAY 0.872340 (1600 925);
PAINT GREEN (1600 925);
DISPLAY INVISIBLE (1600 925);
FORCEPROP 2 LAST CDS_LIB mstr_misc
J 0
(1525 1150);
DISPLAY INVISIBLE (1525 1150);
FORCEADD CAD_NOTE..1
(2825 -150);
FORCEPROP 0 LAST S1 R3955/R3956 CO-LAYOUT
J 0
(2700 -275);
DISPLAY 0.808511 (2700 -275);
PAINT WHITE (2700 -275);
FORCEPROP 1 LAST COMMENT_BODY TRUE
J 0
(2850 -50);
DISPLAY 0.978723 (2850 -50);
DISPLAY INVISIBLE (2850 -50);
FORCEPROP 2 LAST CDS_LIB logical_power
J 0
(2825 -150);
DISPLAY INVISIBLE (2825 -150);
FORCEADD DNS..2
(2250 -1550);
PAINT RED (2250 -1550);
FORCEPROP 2 LAST CDS_LIB mstr_misc
J 0
(2250 -1550);
DISPLAY INVISIBLE (2250 -1550);
FORCEPROP 1 LAST COMMENT_BODY TRUE
R 1
J 0
(2325 -1775);
DISPLAY 0.872340 (2325 -1775);
PAINT GREEN (2325 -1775);
DISPLAY INVISIBLE (2325 -1775);
FORCEADD DNS..2
(1650 -1775);
PAINT RED (1650 -1775);
FORCEPROP 2 LAST CDS_LIB mstr_misc
J 0
(1650 -1775);
DISPLAY INVISIBLE (1650 -1775);
FORCEPROP 1 LAST COMMENT_BODY TRUE
R 1
J 0
(1725 -2000);
DISPLAY 0.872340 (1725 -2000);
PAINT GREEN (1725 -2000);
DISPLAY INVISIBLE (1725 -2000);
FORCEADD DNS..2
(750 -1250);
PAINT RED (750 -1250);
FORCEPROP 2 LAST CDS_LIB mstr_misc
J 0
(750 -1250);
DISPLAY INVISIBLE (750 -1250);
FORCEPROP 1 LAST COMMENT_BODY TRUE
R 1
J 0
(825 -1475);
DISPLAY 0.872340 (825 -1475);
PAINT GREEN (825 -1475);
DISPLAY INVISIBLE (825 -1475);
FORCEADD DNS..2
(150 -1700);
PAINT RED (150 -1700);
FORCEPROP 2 LAST CDS_LIB mstr_misc
J 0
(150 -1700);
DISPLAY INVISIBLE (150 -1700);
FORCEPROP 1 LAST COMMENT_BODY TRUE
R 1
J 0
(225 -1925);
DISPLAY 0.872340 (225 -1925);
PAINT GREEN (225 -1925);
DISPLAY INVISIBLE (225 -1925);
FORCEADD DNS..2
(-425 -1050);
PAINT RED (-425 -1050);
FORCEPROP 2 LAST CDS_LIB mstr_misc
J 0
(-425 -1050);
DISPLAY INVISIBLE (-425 -1050);
FORCEPROP 1 LAST COMMENT_BODY TRUE
R 1
J 0
(-350 -1275);
DISPLAY 0.872340 (-350 -1275);
PAINT GREEN (-350 -1275);
DISPLAY INVISIBLE (-350 -1275);
FORCEADD DNS..2
(-400 -1675);
PAINT RED (-400 -1675);
FORCEPROP 2 LAST CDS_LIB mstr_misc
J 0
(-400 -1675);
DISPLAY INVISIBLE (-400 -1675);
FORCEPROP 1 LAST COMMENT_BODY TRUE
R 1
J 0
(-325 -1900);
DISPLAY 0.872340 (-325 -1900);
PAINT GREEN (-325 -1900);
DISPLAY INVISIBLE (-325 -1900);
FORCEADD DNS..2
(-650 -1325);
PAINT RED (-650 -1325);
FORCEPROP 2 LAST CDS_LIB mstr_misc
J 0
(-650 -1325);
DISPLAY INVISIBLE (-650 -1325);
FORCEPROP 1 LAST COMMENT_BODY TRUE
R 1
J 0
(-575 -1550);
DISPLAY 0.872340 (-575 -1550);
PAINT GREEN (-575 -1550);
DISPLAY INVISIBLE (-575 -1550);
FORCEADD DNS..2
(-725 -1625);
PAINT RED (-725 -1625);
FORCEPROP 2 LAST CDS_LIB mstr_misc
J 0
(-725 -1625);
DISPLAY INVISIBLE (-725 -1625);
FORCEPROP 1 LAST COMMENT_BODY TRUE
R 1
J 0
(-650 -1850);
DISPLAY 0.872340 (-650 -1850);
PAINT GREEN (-650 -1850);
DISPLAY INVISIBLE (-650 -1850);
FORCEADD DNS..2
(-1075 -1625);
PAINT RED (-1075 -1625);
FORCEPROP 2 LAST CDS_LIB mstr_misc
J 0
(-1075 -1625);
DISPLAY INVISIBLE (-1075 -1625);
FORCEPROP 1 LAST COMMENT_BODY TRUE
R 1
J 0
(-1000 -1850);
DISPLAY 0.872340 (-1000 -1850);
PAINT GREEN (-1000 -1850);
DISPLAY INVISIBLE (-1000 -1850);
WIRE 16 -1 (-975 1875)(-975 1775);
WIRE 16 -1 (1050 675)(1525 675);
WIRE 16 -1 (375 1900)(375 1850);
WIRE 16 -1 (2325 1325)(2325 1275);
WIRE 16 -1 (2775 1675)(2775 1725);
WIRE 16 -1 (1500 1675)(2775 1675);
WIRE 16 -1 (2775 1600)(2775 1675);
WIRE 16 -1 (2225 -1225)(2225 -950);
WIRE 16 -1 (1175 -1225)(2225 -1225);
WIRE 16 -1 (2225 -1225)(2225 -1450);
WIRE 16 -1 (-450 -850)(-450 -775);
WIRE 16 -1 (-450 -850)(150 -850);
WIRE 16 -1 (-450 -950)(-450 -850);
WIRE 16 -1 (-2200 425)(-2200 625);
WIRE 16 -1 (-1775 350)(-1775 500);
WIRE 16 -1 (-1425 175)(-1425 100);
WIRE 16 -1 (-825 975)(-1300 975);
WIRE 16 -1 (-825 1075)(-825 975);
WIRE 16 -1 (-825 975)(-500 975);
WIRE 16 -1 (-900 325)(-900 400);
WIRE 16 -1 (-559 491)(-559 575);
WIRE 16 -1 (-975 1400)(-975 1475);
WIRE 16 -1 (975 20)(975 -50);
WIRE 16 -1 (525 20)(975 20);
WIRE 16 -1 (975 20)(975 200);
WIRE 16 -1 (2100 400)(2100 375);
WIRE 16 -1 (1900 400)(2100 400);
WIRE 16 -1 (2100 400)(2425 400);
WIRE 16 -1 (2775 1275)(2775 1400);
WIRE 16 -1 (-1100 -1850)(-1100 -1950);
WIRE 16 -1 (-750 -1850)(-1100 -1850);
WIRE 16 -1 (-1100 -1725)(-1100 -1850);
WIRE 16 -1 (-425 -1775)(-425 -1950);
WIRE 16 -1 (-450 -1150)(-450 -1225);
WIRE 16 -1 (1625 -1950)(1625 -2075);
WIRE 16 -1 (1350 -1950)(1625 -1950);
WIRE 16 -1 (1625 -1875)(1625 -1950);
WIRE 16 -1 (125 -1800)(125 -1950);
WIRE 16 -1 (2225 -1850)(2225 -1650);
WIRE 16 -1 (1875 -25)(2225 -25);
WIRE 16 -1 (1875 150)(1875 -25);
WIRE 16 -1 (2225 150)(1875 150);
WIRE 16 -1 (1600 150)(1875 150);
WIRE 16 -1 (1600 575)(1600 150);
WIRE 16 -1 (975 400)(975 575);
WIRE 16 -1 (975 575)(1600 575);
WIRE 16 -1 (525 400)(525 575);
FORCEPROP 2 LAST SIG_NAME P12V_E1S_IMON_0
J 0
(390 585);
DISPLAY 0.510638 (390 585);
WIRE 16 -1 (525 575)(975 575);
WIRE 16 -1 (300 575)(525 575);
WIRE 16 2175 (1925 -150)(2625 -150);
WIRE 16 2175 (2625 200)(2625 -150);
WIRE 16 2175 (1925 200)(1925 -150);
WIRE 16 2175 (1925 200)(2625 200);
WIRE 16 -1 (2425 -25)(3500 -25);
FORCEPROP 2 LAST SIG_NAME P12V_E1S_0_ISENSE_MPS_TIC
J 0
(2765 -15);
DISPLAY 0.510638 (2765 -15);
WIRE 16 -1 (2425 150)(3525 150);
FORCEPROP 2 LAST SIG_NAME P12V_E1S_0_ISENSE_MPS_MAM
J 0
(2765 160);
DISPLAY 0.510638 (2765 160);
WIRE 16 -1 (2425 1275)(2425 1175);
WIRE 16 -1 (2325 1275)(2425 1275);
WIRE 16 -1 (1900 1275)(2325 1275);
WIRE 16 -1 (1900 1175)(1900 1275);
WIRE 16 -1 (2425 800)(2425 750);
WIRE 16 -1 (2425 975)(2425 800);
WIRE 16 -1 (3025 800)(2425 800);
FORCEPROP 2 LAST SIG_NAME P12V_E1S_AVIN_PD_0
J 0
(2540 810);
DISPLAY 0.510638 (2540 810);
WIRE 16 -1 (2425 400)(2425 550);
WIRE 16 -1 (1900 550)(1900 400);
WIRE 16 -1 (1500 1375)(1500 1250);
WIRE 16 -1 (1500 1375)(1500 1675);
WIRE 16 -1 (900 1250)(900 1375);
WIRE 16 -1 (900 1375)(1500 1375);
WIRE 16 -1 (300 1375)(607 1375);
WIRE 16 -1 (607 1375)(900 1375);
WIRE 16 -1 (300 1325)(607 1325);
WIRE 16 -1 (607 1325)(607 1375);
WIRE 16 -1 (300 1275)(607 1275);
WIRE 16 -1 (607 1275)(607 1325);
WIRE 16 -1 (300 1225)(607 1225);
WIRE 16 -1 (607 1225)(607 1275);
WIRE 16 -1 (607 1175)(300 1175);
WIRE 16 -1 (607 1175)(607 1225);
WIRE 16 -1 (300 1125)(607 1125);
WIRE 16 -1 (607 1125)(607 1175);
WIRE 16 -1 (300 1075)(607 1075);
WIRE 16 -1 (607 1075)(607 1125);
WIRE 16 -1 (607 1075)(607 1025);
WIRE 16 -1 (300 1025)(607 1025);
WIRE 16 -1 (1900 825)(1900 750);
WIRE 16 -1 (1900 975)(1900 825);
WIRE 16 -1 (1900 825)(1500 825);
WIRE 16 -1 (1500 1050)(1500 825);
WIRE 16 -1 (300 825)(1500 825);
FORCEPROP 2 LAST SIG_NAME P12V_E1S_OV_FB_0
J 0
(390 835);
DISPLAY 0.510638 (390 835);
WIRE 16 -1 (525 200)(525 20);
WIRE 16 -1 (850 675)(300 675);
FORCEPROP 2 LAST SIG_NAME P12V_E1S_FLTB_0
J 0
(390 685);
DISPLAY 0.510638 (390 685);
WIRE 16 -1 (900 1050)(900 925);
WIRE 16 -1 (900 925)(1050 925);
WIRE 16 -1 (300 925)(900 925);
FORCEPROP 2 LAST SIG_NAME P12V_E1S_AVIN_PD_0
J 0
(390 935);
DISPLAY 0.510638 (390 935);
WIRE 16 -1 (375 1650)(375 1525);
WIRE 16 -1 (1125 1525)(375 1525);
FORCEPROP 2 LAST SIG_NAME HP_LVC3_E1S_0_HSC_PWRGD
J 0
(415 1535);
DISPLAY 0.510638 (415 1535);
WIRE 16 -1 (300 1525)(375 1525);
WIRE 16 -1 (-975 1775)(-975 1675);
WIRE 16 -1 (-580 1775)(-975 1775);
WIRE 16 -1 (-580 1775)(-580 1525);
WIRE 16 -1 (-580 1525)(-500 1525);
WIRE 16 -1 (-580 1475)(-580 1525);
WIRE 16 -1 (-500 1475)(-580 1475);
WIRE 16 -1 (-580 1425)(-580 1475);
WIRE 16 -1 (-500 1425)(-580 1425);
WIRE 16 -1 (-580 1375)(-580 1425);
WIRE 16 -1 (-500 1375)(-580 1375);
WIRE 16 -1 (-580 1325)(-580 1375);
WIRE 16 -1 (-500 1325)(-580 1325);
WIRE 16 3135 (-2100 2100)(-2100 1500);
WIRE 16 3135 (-1675 2100)(-1675 1500);
WIRE 16 -1 (-500 1075)(-825 1075);
WIRE 16 -1 (-900 675)(-900 600);
WIRE 16 -1 (-500 675)(-900 675);
FORCEPROP 2 LAST SIG_NAME P12V_E1S_SS_0
J 0
(-935 685);
DISPLAY 0.510638 (-935 685);
WIRE 16 -1 (-559 575)(-500 575);
WIRE 16 -1 (-1325 1175)(-500 1175);
FORCEPROP 2 LAST SIG_NAME P12V_E1S_EN_0_R2
J 0
(-1010 1185);
DISPLAY 0.510638 (-1010 1185);
WIRE 16 -1 (-1775 775)(-1775 700);
WIRE 16 -1 (-1425 775)(-1775 775);
FORCEPROP 2 LAST SIG_NAME P12V_E1S_ISET_0
J 0
(-1460 785);
DISPLAY 0.510638 (-1460 785);
WIRE 16 -1 (-1425 775)(-1425 700);
WIRE 16 -1 (-500 775)(-1425 775);
WIRE 16 -1 (-1425 500)(-1425 375);
FORCEPROP 2 LAST SIG_NAME P12V_E1S_ISET_0_R
J 0
(-1385 435);
DISPLAY 0.510638 (-1385 435);
WIRE 16 3135 (-2450 1875)(-1250 1875);
WIRE 16 3135 (-2450 1975)(-1250 1975);
WIRE 16 -1 (-1525 1175)(-2200 1175);
FORCEPROP 2 LAST SIG_NAME E1S_0_EN
J 0
(-2160 1185);
DISPLAY 0.510638 (-2160 1185);
WIRE 16 3135 (-2475 2125)(-1225 2125);
WIRE 16 3135 (-1225 1475)(-1225 2125);
WIRE 16 3135 (-2475 1475)(-2475 2125);
WIRE 16 3135 (-2475 1475)(-1225 1475);
WIRE 16 3135 (-2450 1575)(-1250 1575);
WIRE 16 3135 (-2450 1675)(-1250 1675);
WIRE 16 3135 (-2450 1775)(-1250 1775);
WIRE 16 -1 (-2200 875)(-2200 825);
WIRE 16 -1 (-500 875)(-2200 875);
FORCEPROP 2 LAST SIG_NAME P12V_E1S_TIMER_0
J 0
(-1010 885);
DISPLAY 0.510638 (-1010 885);
WIRE 16 -1 (1175 -1425)(1625 -1425);
FORCEPROP 2 LAST SIG_NAME P3V3_E1S_GATE_0_PU293
J 0
(1265 -1415);
DISPLAY 0.510638 (1265 -1415);
WIRE 16 -1 (1625 -1675)(1625 -1425);
WIRE 16 -1 (1350 -1525)(1350 -1950);
WIRE 16 -1 (1175 -1525)(1350 -1525);
WIRE 16 -1 (150 -1225)(375 -1225);
WIRE 16 -1 (150 -850)(150 -1225);
WIRE 16 -1 (125 -1600)(125 -1525);
FORCEPROP 2 LAST SIG_NAME P3V3_E1S_DVDT_0
J 0
(-160 -1515);
DISPLAY 0.510638 (-160 -1515);
WIRE 16 -1 (125 -1525)(375 -1525);
WIRE 16 -1 (-1100 -1525)(-1100 -1425);
WIRE 16 -1 (-1100 -1425)(-750 -1425);
WIRE 16 -1 (375 -1425)(-750 -1425);
FORCEPROP 2 LAST SIG_NAME P3V3_E1S_MODE_0
J 0
(-160 -1415);
DISPLAY 0.510638 (-160 -1415);
WIRE 16 -1 (-750 -1525)(-750 -1425);
WIRE 16 -1 (375 -1325)(-575 -1325);
FORCEPROP 2 LAST SIG_NAME P3V3_E1S_EN_0_R2
J 0
(-185 -1315);
DISPLAY 0.510638 (-185 -1315);
WIRE 16 -1 (-425 -1575)(-425 -1475);
WIRE 16 -1 (-425 -1475)(375 -1475);
FORCEPROP 2 LAST SIG_NAME P3V3_E1S_ILIMIT_0
J 0
(-210 -1465);
DISPLAY 0.510638 (-210 -1465);
WIRE 16 2175 (-4650 3225)(-2947 3225);
WIRE 16 2175 (-2947 3225)(-2947 2325);
WIRE 16 2175 (-4650 3225)(-4650 2325);
WIRE 16 2175 (-4650 2325)(-2947 2325);
WIRE 16 -1 (-750 -1725)(-750 -1850);
WIRE 16 -1 (-775 -1325)(-1550 -1325);
FORCEPROP 2 LAST SIG_NAME E1S_0_EN
J 0
(-1535 -1315);
DISPLAY 0.510638 (-1535 -1315);
DOT 1 (-1100 -1850);
DOT 1 (-750 -1425);
DOT 1 (-450 -850);
DOT 1 (1625 -1950);
DOT 1 (2225 -1225);
DOT 1 (-1425 775);
DOT 1 (-825 975);
DOT 1 (-580 1375);
DOT 1 (-580 1425);
DOT 1 (-580 1475);
DOT 1 (-580 1525);
DOT 1 (-975 1775);
DOT 1 (525 575);
DOT 1 (375 1525);
DOT 1 (607 1075);
DOT 1 (900 925);
DOT 1 (607 1125);
DOT 1 (607 1175);
DOT 1 (607 1225);
DOT 1 (607 1275);
DOT 1 (607 1325);
DOT 1 (607 1375);
DOT 1 (900 1375);
DOT 1 (975 20);
DOT 1 (1875 150);
DOT 1 (975 575);
DOT 1 (1500 825);
DOT 1 (1900 825);
DOT 1 (1500 1375);
DOT 1 (2100 400);
DOT 1 (2425 800);
DOT 1 (2325 1275);
DOT 1 (2775 1675);
FORCENOTE
=0.75A
(-725 -2200) 0;
DISPLAY LEFT (-725 -2200);
DISPLAY 0.510638 (-725 -2200);
PAINT WHITE (-725 -2200);
FORCENOTE
CURRENT LIMIT
(-725 -2134) 0;
DISPLAY LEFT (-725 -2134);
DISPLAY 0.510638 (-725 -2134);
PAINT WHITE (-725 -2134);
FORCENOTE
P12V_E1S_0
(-4600 3050) 0;
DISPLAY LEFT (-4600 3050);
DISPLAY 0.510638 (-4600 3050);
FORCENOTE
OCP=0.75A
(-4600 2525) 0;
DISPLAY LEFT (-4600 2525);
DISPLAY 0.510638 (-4600 2525);
FORCENOTE
P3V3_E1S_0_R
(-4600 2675) 0;
DISPLAY LEFT (-4600 2675);
DISPLAY 0.510638 (-4600 2675);
FORCENOTE
IMAX=2.083A
(-4600 2975) 0;
DISPLAY LEFT (-4600 2975);
DISPLAY 0.510638 (-4600 2975);
FORCENOTE
OCP=MAX*1.3=2.71A
(-4600 2900) 0;
DISPLAY LEFT (-4600 2900);
DISPLAY 0.510638 (-4600 2900);
FORCENOTE
DESIGN SPECIFICATION
(-4613 3144) 0;
DISPLAY LEFT (-4613 3144);
DISPLAY 0.510638 (-4613 3144);
FORCENOTE
START UP TIME:4.7MS
(350 -2250) 0;
DISPLAY LEFT (350 -2250);
DISPLAY 0.510638 (350 -2250);
PAINT WHITE (350 -2250);
FORCENOTE
IMAX=0.025A
(-4600 2600) 0;
DISPLAY LEFT (-4600 2600);
DISPLAY 0.510638 (-4600 2600);
FORCENOTE
ENABLE:
(-2675 1025) 0;
DISPLAY LEFT (-2675 1025);
DISPLAY 1.021277 (-2675 1025);
PAINT WHITE (-2675 1025);
FORCENOTE
PU292 OPTIONAL BOM
(-2450 2150) 0;
DISPLAY LEFT (-2450 2150);
DISPLAY 1.021277 (-2450 2150);
FORCENOTE
PR3957
(-2400 1600) 0;
DISPLAY LEFT (-2400 1600);
DISPLAY 1.021277 (-2400 1600);
FORCENOTE
PR3953
(-2400 1700) 0;
DISPLAY LEFT (-2400 1700);
DISPLAY 1.021277 (-2400 1700);
FORCENOTE
PR3952
(-2400 1800) 0;
DISPLAY LEFT (-2400 1800);
DISPLAY 1.021277 (-2400 1800);
FORCENOTE
PC2205
(-2400 1500) 0;
DISPLAY LEFT (-2400 1500);
DISPLAY 1.021277 (-2400 1500);
FORCENOTE
PR3950
(-2400 1900) 0;
DISPLAY LEFT (-2400 1900);
DISPLAY 1.021277 (-2400 1900);
FORCENOTE
TDELAY: 6.29MS
(-2725 125) 0;
DISPLAY LEFT (-2725 125);
DISPLAY 1.021277 (-2725 125);
PAINT WHITE (-2725 125);
FORCENOTE
TFAULT: 1.27MS
(-2725 200) 0;
DISPLAY LEFT (-2725 200);
DISPLAY 1.021277 (-2725 200);
PAINT WHITE (-2725 200);
FORCENOTE
VTH>1.391V(HIGH)
(-2675 959) 0;
DISPLAY LEFT (-2675 959);
DISPLAY 1.021277 (-2675 959);
PAINT WHITE (-2675 959);
FORCENOTE
POP
(-2050 1500) 0;
DISPLAY LEFT (-2050 1500);
DISPLAY 1.021277 (-2050 1500);
FORCENOTE
DE-POP
(-1625 1500) 0;
DISPLAY LEFT (-1625 1500);
DISPLAY 1.021277 (-1625 1500);
FORCENOTE
POP
(-2050 1600) 0;
DISPLAY LEFT (-2050 1600);
DISPLAY 1.021277 (-2050 1600);
FORCENOTE
POP
(-2050 1700) 0;
DISPLAY LEFT (-2050 1700);
DISPLAY 1.021277 (-2050 1700);
FORCENOTE
MP5025C/
(-2075 2050) 0;
DISPLAY LEFT (-2075 2050);
DISPLAY 1.021277 (-2075 2050);
FORCENOTE
MP5022C
(-2075 2000) 0;
DISPLAY LEFT (-2075 2000);
DISPLAY 1.021277 (-2075 2000);
FORCENOTE
DE-POP
(-2050 1900) 0;
DISPLAY LEFT (-2050 1900);
DISPLAY 1.021277 (-2050 1900);
FORCENOTE
DE-POP
(-2050 1800) 0;
DISPLAY LEFT (-2050 1800);
DISPLAY 1.021277 (-2050 1800);
FORCENOTE
DE-POP
(-1625 1600) 0;
DISPLAY LEFT (-1625 1600);
DISPLAY 1.021277 (-1625 1600);
FORCENOTE
DE-POP
(-1625 1700) 0;
DISPLAY LEFT (-1625 1700);
DISPLAY 1.021277 (-1625 1700);
FORCENOTE
MP5022A
(-1625 2000) 0;
DISPLAY LEFT (-1625 2000);
DISPLAY 1.021277 (-1625 2000);
FORCENOTE
MP5025A/
(-1625 2050) 0;
DISPLAY LEFT (-1625 2050);
DISPLAY 1.021277 (-1625 2050);
FORCENOTE
POP
(-1575 1900) 0;
DISPLAY LEFT (-1575 1900);
DISPLAY 1.021277 (-1575 1900);
FORCENOTE
POP
(-1575 1800) 0;
DISPLAY LEFT (-1575 1800);
DISPLAY 1.021277 (-1575 1800);
FORCENOTE
VIMON(MAX)= 1.569V @ IOUT=2.8A
(-625 -175) 0;
DISPLAY LEFT (-625 -175);
DISPLAY 1.021277 (-625 -175);
PAINT WHITE (-625 -175);
FORCENOTE
START UP TIME:8.62MS
(-925 100) 0;
DISPLAY LEFT (-925 100);
DISPLAY 1.021277 (-925 100);
PAINT WHITE (-925 100);
QUIT
